FILE_TYPE = MACRO_DRAWING;
SET COLOR_WIRE YELLOW;
SET COLOR_PROP MONO;
SET COLOR_DOT WHITE;
SET COLOR_ARC YELLOW;
SET COLOR_BODY GREEN;
SET COLOR_NOTE MONO;
SET PROP_DISPLAY VALUE;
SET PAGE_NUMBER P46;
FORCEADD GND..1
(-2975 650);
FORCEPROP 3 LASTPIN (-2975 700) SIG_NAME GND\g
J 0
(-2965 710);
DISPLAY 0.659574 (-2965 710);
PAINT MONO (-2965 710);
DISPLAY INVISIBLE (-2965 710);
FORCEPROP 1 LAST HDL_POWER GND
J 0
(-2975 800);
DISPLAY 1.404255 (-2975 800);
PAINT GREEN (-2975 800);
DISPLAY INVISIBLE (-2975 800);
FORCEPROP 2 LAST ROOM DDR4_CH_A
J 0
(-2975 655);
PAINT ORANGE (-2975 655);
DISPLAY INVISIBLE (-2975 655);
FORCEPROP 1 LAST PATH I1
J 0
(-2900 650);
DISPLAY 0.872340 (-2900 650);
PAINT AQUA (-2900 650);
DISPLAY INVISIBLE (-2900 650);
FORCEPROP 1 LAST BODY_TYPE PLUMBING
J 0
(-3020 607);
DISPLAY 0.340426 (-3020 607);
PAINT GREEN (-3020 607);
DISPLAY INVISIBLE (-3020 607);
FORCEPROP 2 LAST CDS_LIB mstr_symbols
J 0
(-2975 650);
PAINT ORANGE (-2975 650);
DISPLAY INVISIBLE (-2975 650);
FORCEPROP 1 LAST SIZE 1B
J 0
(-2900 600);
DISPLAY 1.787234 (-2900 600);
PAINT GREEN (-2900 600);
DISPLAY INVISIBLE (-2900 600);
FORCEPROP 2 LAST BOM_COST MEM
J 0
(-2975 655);
PAINT ORANGE (-2975 655);
DISPLAY INVISIBLE (-2975 655);
FORCEPROP 1 LAST VOLTAGE 0
J 0
(-2975 650);
PAINT SKYBLUE (-2975 650);
DISPLAY INVISIBLE (-2975 650);
FORCEADD OFFPAGE..1
(-2375 3100);
FORCEPROP 2 LAST $XR1 45 
J 0
(-2686 3100);
DISPLAY 0.638298 (-2686 3100);
PAINT MONO (-2686 3100);
FORCEPROP 2 LAST $XR0 24 
J 0
(-2596 3100);
DISPLAY 0.638298 (-2596 3100);
PAINT MONO (-2596 3100);
FORCEPROP 2 LAST PATH I10
J 0
(-2575 3150);
DISPLAY 1.021277 (-2575 3150);
PAINT ORANGE (-2575 3150);
DISPLAY INVISIBLE (-2575 3150);
FORCEPROP 1 LAST COMMENT_BODY TRUE
J 0
(-2250 3000);
DISPLAY 0.936170 (-2250 3000);
PAINT GREEN (-2250 3000);
DISPLAY INVISIBLE (-2250 3000);
FORCEPROP 1 LAST OFFPAGE TRUE
J 0
(-2050 2975);
DISPLAY 0.936170 (-2050 2975);
PAINT GREEN (-2050 2975);
DISPLAY INVISIBLE (-2050 2975);
FORCEPROP 2 LAST CDS_LIB mstr_standard
J 0
(-2375 3100);
DISPLAY 0.787234 (-2375 3100);
PAINT MONO (-2375 3100);
DISPLAY INVISIBLE (-2375 3100);
FORCEADD TAP..6
R 2
(-75 3250);
FORCEPROP 3 LASTPIN (-125 3250) SIG_NAME M_B_DQ<43>
J 0
(-115 3260);
DISPLAY 0.659574 (-115 3260);
PAINT MONO (-115 3260);
DISPLAY INVISIBLE (-115 3260);
FORCEPROP 1 LASTPIN (-125 3250) BN 43
J 2
(-75 3260);
DISPLAY 0.617021 (-75 3260);
PAINT PINK (-75 3260);
FORCEPROP 1 LAST PATH I100
J 2
(-73 3250);
DISPLAY 0.872340 (-73 3250);
PAINT GREEN (-73 3250);
DISPLAY INVISIBLE (-73 3250);
FORCEPROP 1 LAST HDL_TAP TRUE
J 2
(-400 3125);
DISPLAY 1.234043 (-400 3125);
PAINT GREEN (-400 3125);
DISPLAY INVISIBLE (-400 3125);
FORCEPROP 1 LAST BODY_TYPE PLUMBING
J 2
(-75 3200);
DISPLAY 1.234043 (-75 3200);
PAINT GREEN (-75 3200);
DISPLAY INVISIBLE (-75 3200);
FORCEPROP 2 LAST CDS_LIB mstr_standard
J 2
(-75 3250);
DISPLAY 0.787234 (-75 3250);
PAINT MONO (-75 3250);
DISPLAY INVISIBLE (-75 3250);
FORCEADD TAP..6
R 2
(-75 3350);
FORCEPROP 3 LASTPIN (-125 3350) SIG_NAME M_B_DQ<45>
J 0
(-115 3360);
DISPLAY 0.659574 (-115 3360);
PAINT MONO (-115 3360);
DISPLAY INVISIBLE (-115 3360);
FORCEPROP 1 LASTPIN (-125 3350) BN 45
J 2
(-75 3360);
DISPLAY 0.617021 (-75 3360);
PAINT PINK (-75 3360);
FORCEPROP 1 LAST PATH I101
J 2
(-73 3350);
DISPLAY 0.872340 (-73 3350);
PAINT GREEN (-73 3350);
DISPLAY INVISIBLE (-73 3350);
FORCEPROP 1 LAST HDL_TAP TRUE
J 2
(-400 3225);
DISPLAY 1.234043 (-400 3225);
PAINT GREEN (-400 3225);
DISPLAY INVISIBLE (-400 3225);
FORCEPROP 1 LAST BODY_TYPE PLUMBING
J 2
(-75 3300);
DISPLAY 1.234043 (-75 3300);
PAINT GREEN (-75 3300);
DISPLAY INVISIBLE (-75 3300);
FORCEPROP 2 LAST CDS_LIB mstr_standard
J 2
(-75 3350);
DISPLAY 0.787234 (-75 3350);
PAINT MONO (-75 3350);
DISPLAY INVISIBLE (-75 3350);
FORCEADD TAP..6
R 2
(-75 3450);
FORCEPROP 3 LASTPIN (-125 3450) SIG_NAME M_B_DQ<47>
J 0
(-115 3460);
DISPLAY 0.659574 (-115 3460);
PAINT MONO (-115 3460);
DISPLAY INVISIBLE (-115 3460);
FORCEPROP 1 LASTPIN (-125 3450) BN 47
J 2
(-75 3460);
DISPLAY 0.617021 (-75 3460);
PAINT PINK (-75 3460);
FORCEPROP 1 LAST PATH I102
J 2
(-73 3450);
DISPLAY 0.872340 (-73 3450);
PAINT GREEN (-73 3450);
DISPLAY INVISIBLE (-73 3450);
FORCEPROP 1 LAST HDL_TAP TRUE
J 2
(-400 3325);
DISPLAY 1.234043 (-400 3325);
PAINT GREEN (-400 3325);
DISPLAY INVISIBLE (-400 3325);
FORCEPROP 1 LAST BODY_TYPE PLUMBING
J 2
(-75 3400);
DISPLAY 1.234043 (-75 3400);
PAINT GREEN (-75 3400);
DISPLAY INVISIBLE (-75 3400);
FORCEPROP 2 LAST CDS_LIB mstr_standard
J 2
(-75 3450);
DISPLAY 0.787234 (-75 3450);
PAINT MONO (-75 3450);
DISPLAY INVISIBLE (-75 3450);
FORCEADD TAP..6
R 2
(-75 3400);
FORCEPROP 3 LASTPIN (-125 3400) SIG_NAME M_B_DQ<46>
J 0
(-115 3410);
DISPLAY 0.659574 (-115 3410);
PAINT MONO (-115 3410);
DISPLAY INVISIBLE (-115 3410);
FORCEPROP 1 LASTPIN (-125 3400) BN 46
J 2
(-75 3410);
DISPLAY 0.617021 (-75 3410);
PAINT PINK (-75 3410);
FORCEPROP 1 LAST PATH I103
J 2
(-73 3400);
DISPLAY 0.872340 (-73 3400);
PAINT GREEN (-73 3400);
DISPLAY INVISIBLE (-73 3400);
FORCEPROP 1 LAST HDL_TAP TRUE
J 2
(-400 3275);
DISPLAY 1.234043 (-400 3275);
PAINT GREEN (-400 3275);
DISPLAY INVISIBLE (-400 3275);
FORCEPROP 1 LAST BODY_TYPE PLUMBING
J 2
(-75 3350);
DISPLAY 1.234043 (-75 3350);
PAINT GREEN (-75 3350);
DISPLAY INVISIBLE (-75 3350);
FORCEPROP 2 LAST CDS_LIB mstr_standard
J 2
(-75 3400);
DISPLAY 0.787234 (-75 3400);
PAINT MONO (-75 3400);
DISPLAY INVISIBLE (-75 3400);
FORCEADD TAP..6
R 2
(-75 3550);
FORCEPROP 3 LASTPIN (-125 3550) SIG_NAME M_B_DQ<49>
J 0
(-115 3560);
DISPLAY 0.659574 (-115 3560);
PAINT MONO (-115 3560);
DISPLAY INVISIBLE (-115 3560);
FORCEPROP 1 LASTPIN (-125 3550) BN 49
J 2
(-75 3560);
DISPLAY 0.617021 (-75 3560);
PAINT PINK (-75 3560);
FORCEPROP 1 LAST PATH I104
J 2
(-73 3550);
DISPLAY 0.872340 (-73 3550);
PAINT GREEN (-73 3550);
DISPLAY INVISIBLE (-73 3550);
FORCEPROP 1 LAST HDL_TAP TRUE
J 2
(-400 3425);
DISPLAY 1.234043 (-400 3425);
PAINT GREEN (-400 3425);
DISPLAY INVISIBLE (-400 3425);
FORCEPROP 1 LAST BODY_TYPE PLUMBING
J 2
(-75 3500);
DISPLAY 1.234043 (-75 3500);
PAINT GREEN (-75 3500);
DISPLAY INVISIBLE (-75 3500);
FORCEPROP 2 LAST CDS_LIB mstr_standard
J 2
(-75 3550);
DISPLAY 0.787234 (-75 3550);
PAINT MONO (-75 3550);
DISPLAY INVISIBLE (-75 3550);
FORCEADD TAP..6
R 2
(-75 3500);
FORCEPROP 3 LASTPIN (-125 3500) SIG_NAME M_B_DQ<48>
J 0
(-115 3510);
DISPLAY 0.659574 (-115 3510);
PAINT MONO (-115 3510);
DISPLAY INVISIBLE (-115 3510);
FORCEPROP 1 LASTPIN (-125 3500) BN 48
J 2
(-75 3510);
DISPLAY 0.617021 (-75 3510);
PAINT PINK (-75 3510);
FORCEPROP 1 LAST PATH I105
J 2
(-73 3500);
DISPLAY 0.872340 (-73 3500);
PAINT GREEN (-73 3500);
DISPLAY INVISIBLE (-73 3500);
FORCEPROP 1 LAST HDL_TAP TRUE
J 2
(-400 3375);
DISPLAY 1.234043 (-400 3375);
PAINT GREEN (-400 3375);
DISPLAY INVISIBLE (-400 3375);
FORCEPROP 1 LAST BODY_TYPE PLUMBING
J 2
(-75 3450);
DISPLAY 1.234043 (-75 3450);
PAINT GREEN (-75 3450);
DISPLAY INVISIBLE (-75 3450);
FORCEPROP 2 LAST CDS_LIB mstr_standard
J 2
(-75 3500);
DISPLAY 0.787234 (-75 3500);
PAINT MONO (-75 3500);
DISPLAY INVISIBLE (-75 3500);
FORCEADD TAP..6
R 2
(-75 3600);
FORCEPROP 3 LASTPIN (-125 3600) SIG_NAME M_B_DQ<50>
J 0
(-115 3610);
DISPLAY 0.659574 (-115 3610);
PAINT MONO (-115 3610);
DISPLAY INVISIBLE (-115 3610);
FORCEPROP 1 LASTPIN (-125 3600) BN 50
J 2
(-75 3610);
DISPLAY 0.617021 (-75 3610);
PAINT PINK (-75 3610);
FORCEPROP 1 LAST PATH I106
J 2
(-73 3600);
DISPLAY 0.872340 (-73 3600);
PAINT GREEN (-73 3600);
DISPLAY INVISIBLE (-73 3600);
FORCEPROP 1 LAST HDL_TAP TRUE
J 2
(-400 3475);
DISPLAY 1.234043 (-400 3475);
PAINT GREEN (-400 3475);
DISPLAY INVISIBLE (-400 3475);
FORCEPROP 1 LAST BODY_TYPE PLUMBING
J 2
(-75 3550);
DISPLAY 1.234043 (-75 3550);
PAINT GREEN (-75 3550);
DISPLAY INVISIBLE (-75 3550);
FORCEPROP 2 LAST CDS_LIB mstr_standard
J 2
(-75 3600);
DISPLAY 0.787234 (-75 3600);
PAINT MONO (-75 3600);
DISPLAY INVISIBLE (-75 3600);
FORCEADD TAP..6
R 2
(-75 3650);
FORCEPROP 3 LASTPIN (-125 3650) SIG_NAME M_B_DQ<51>
J 0
(-115 3660);
DISPLAY 0.659574 (-115 3660);
PAINT MONO (-115 3660);
DISPLAY INVISIBLE (-115 3660);
FORCEPROP 1 LASTPIN (-125 3650) BN 51
J 2
(-75 3660);
DISPLAY 0.617021 (-75 3660);
PAINT PINK (-75 3660);
FORCEPROP 1 LAST PATH I107
J 2
(-73 3650);
DISPLAY 0.872340 (-73 3650);
PAINT GREEN (-73 3650);
DISPLAY INVISIBLE (-73 3650);
FORCEPROP 1 LAST HDL_TAP TRUE
J 2
(-400 3525);
DISPLAY 1.234043 (-400 3525);
PAINT GREEN (-400 3525);
DISPLAY INVISIBLE (-400 3525);
FORCEPROP 1 LAST BODY_TYPE PLUMBING
J 2
(-75 3600);
DISPLAY 1.234043 (-75 3600);
PAINT GREEN (-75 3600);
DISPLAY INVISIBLE (-75 3600);
FORCEPROP 2 LAST CDS_LIB mstr_standard
J 2
(-75 3650);
DISPLAY 0.787234 (-75 3650);
PAINT MONO (-75 3650);
DISPLAY INVISIBLE (-75 3650);
FORCEADD TAP..6
R 2
(-75 3700);
FORCEPROP 3 LASTPIN (-125 3700) SIG_NAME M_B_DQ<52>
J 0
(-115 3710);
DISPLAY 0.659574 (-115 3710);
PAINT MONO (-115 3710);
DISPLAY INVISIBLE (-115 3710);
FORCEPROP 1 LASTPIN (-125 3700) BN 52
J 2
(-75 3710);
DISPLAY 0.617021 (-75 3710);
PAINT PINK (-75 3710);
FORCEPROP 1 LAST PATH I108
J 2
(-73 3700);
DISPLAY 0.872340 (-73 3700);
PAINT GREEN (-73 3700);
DISPLAY INVISIBLE (-73 3700);
FORCEPROP 1 LAST HDL_TAP TRUE
J 2
(-400 3575);
DISPLAY 1.234043 (-400 3575);
PAINT GREEN (-400 3575);
DISPLAY INVISIBLE (-400 3575);
FORCEPROP 1 LAST BODY_TYPE PLUMBING
J 2
(-75 3650);
DISPLAY 1.234043 (-75 3650);
PAINT GREEN (-75 3650);
DISPLAY INVISIBLE (-75 3650);
FORCEPROP 2 LAST CDS_LIB mstr_standard
J 2
(-75 3700);
DISPLAY 0.787234 (-75 3700);
PAINT MONO (-75 3700);
DISPLAY INVISIBLE (-75 3700);
FORCEADD PVDDQ_ABC..1
(600 2200);
FORCEPROP 3 LASTPIN (600 2150) SIG_NAME PVDDQ_ABC\g
J 0
(610 2160);
DISPLAY 0.659574 (610 2160);
PAINT MONO (610 2160);
DISPLAY INVISIBLE (610 2160);
FORCEPROP 1 LAST HDL_POWER PVDDQ_ABC
J 1
(600 2250);
DISPLAY 0.872340 (600 2250);
PAINT GREEN (600 2250);
DISPLAY INVISIBLE (600 2250);
FORCEPROP 2 LAST ROOM DDR4_CH_A
J 0
(600 2300);
DISPLAY 0.787234 (600 2300);
PAINT ORANGE (600 2300);
DISPLAY INVISIBLE (600 2300);
FORCEPROP 1 LAST PATH I109
J 0
(650 2225);
DISPLAY 0.872340 (650 2225);
PAINT AQUA (650 2225);
DISPLAY INVISIBLE (650 2225);
FORCEPROP 1 LAST BODY_TYPE PLUMBING
J 0
(555 2157);
DISPLAY 0.340426 (555 2157);
PAINT GREEN (555 2157);
DISPLAY INVISIBLE (555 2157);
FORCEPROP 2 LAST CDS_LIB mstr_symbols
J 0
(600 2200);
PAINT ORANGE (600 2200);
DISPLAY INVISIBLE (600 2200);
FORCEPROP 2 LAST BOM_COST MEM
J 0
(600 2205);
PAINT ORANGE (600 2205);
DISPLAY INVISIBLE (600 2205);
FORCEPROP 1 LAST VOLTAGE 1.2V
J 0
(555 2157);
DISPLAY 0.340426 (555 2157);
PAINT SKYBLUE (555 2157);
DISPLAY INVISIBLE (555 2157);
FORCEADD OFFPAGE..1
(-2225 800);
FORCEPROP 2 LAST $XR5 48 
J 0
(-2926 800);
DISPLAY 0.638298 (-2926 800);
PAINT MONO (-2926 800);
FORCEPROP 2 LAST $XR4 47 
J 0
(-2836 800);
DISPLAY 0.638298 (-2836 800);
PAINT MONO (-2836 800);
FORCEPROP 2 LAST $XR3 45 
J 0
(-2746 800);
DISPLAY 0.638298 (-2746 800);
PAINT MONO (-2746 800);
FORCEPROP 2 LAST $XR2 44 
J 0
(-2656 800);
DISPLAY 0.638298 (-2656 800);
PAINT MONO (-2656 800);
FORCEPROP 2 LAST $XR1 43 
J 0
(-2566 800);
DISPLAY 0.638298 (-2566 800);
PAINT MONO (-2566 800);
FORCEPROP 2 LAST $XR0 89 
J 0
(-2476 800);
DISPLAY 0.638298 (-2476 800);
PAINT MONO (-2476 800);
FORCEPROP 2 LAST PATH I11
J 0
(-2475 850);
DISPLAY 1.021277 (-2475 850);
PAINT ORANGE (-2475 850);
DISPLAY INVISIBLE (-2475 850);
FORCEPROP 1 LAST COMMENT_BODY TRUE
J 0
(-2100 700);
DISPLAY 0.936170 (-2100 700);
PAINT GREEN (-2100 700);
DISPLAY INVISIBLE (-2100 700);
FORCEPROP 1 LAST OFFPAGE TRUE
J 0
(-1900 675);
DISPLAY 0.936170 (-1900 675);
PAINT GREEN (-1900 675);
DISPLAY INVISIBLE (-1900 675);
FORCEPROP 2 LAST CDS_LIB mstr_standard
J 0
(-2225 800);
PAINT ORANGE (-2225 800);
DISPLAY INVISIBLE (-2225 800);
FORCEADD PVTT_ABC..1
(825 2350);
FORCEPROP 3 LASTPIN (825 2300) SIG_NAME PVTT_ABC\g
J 0
(835 2310);
DISPLAY 0.659574 (835 2310);
PAINT MONO (835 2310);
DISPLAY INVISIBLE (835 2310);
FORCEPROP 1 LAST HDL_POWER PVTT_ABC
J 1
(825 2400);
DISPLAY 0.872340 (825 2400);
PAINT GREEN (825 2400);
DISPLAY INVISIBLE (825 2400);
FORCEPROP 2 LAST ROOM DDR4_CH_A
J 0
(825 2450);
DISPLAY 0.787234 (825 2450);
PAINT ORANGE (825 2450);
DISPLAY INVISIBLE (825 2450);
FORCEPROP 1 LAST PATH I110
J 0
(875 2375);
DISPLAY 0.872340 (875 2375);
PAINT AQUA (875 2375);
DISPLAY INVISIBLE (875 2375);
FORCEPROP 1 LAST BODY_TYPE PLUMBING
J 0
(780 2307);
DISPLAY 0.340426 (780 2307);
PAINT GREEN (780 2307);
DISPLAY INVISIBLE (780 2307);
FORCEPROP 2 LAST CDS_LIB mstr_symbols
J 0
(825 2350);
PAINT ORANGE (825 2350);
DISPLAY INVISIBLE (825 2350);
FORCEPROP 2 LAST BOM_COST MEM
J 0
(825 2355);
PAINT ORANGE (825 2355);
DISPLAY INVISIBLE (825 2355);
FORCEPROP 1 LAST VOLTAGE 0.6V
J 0
(780 2307);
DISPLAY 0.340426 (780 2307);
PAINT SKYBLUE (780 2307);
DISPLAY INVISIBLE (780 2307);
FORCEADD PVPP_ABC..1
(975 2650);
FORCEPROP 3 LASTPIN (975 2600) SIG_NAME PVPP_ABC\g
J 0
(985 2610);
DISPLAY 0.659574 (985 2610);
PAINT MONO (985 2610);
DISPLAY INVISIBLE (985 2610);
FORCEPROP 1 LAST HDL_POWER PVPP_ABC
J 1
(975 2700);
DISPLAY 0.872340 (975 2700);
PAINT GREEN (975 2700);
DISPLAY INVISIBLE (975 2700);
FORCEPROP 2 LAST ROOM DDR4_CH_A
J 0
(975 2750);
PAINT ORANGE (975 2750);
DISPLAY INVISIBLE (975 2750);
FORCEPROP 1 LAST PATH I111
J 0
(1025 2675);
DISPLAY 0.872340 (1025 2675);
PAINT AQUA (1025 2675);
DISPLAY INVISIBLE (1025 2675);
FORCEPROP 1 LAST BODY_TYPE PLUMBING
J 0
(930 2607);
DISPLAY 0.340426 (930 2607);
PAINT GREEN (930 2607);
DISPLAY INVISIBLE (930 2607);
FORCEPROP 2 LAST CDS_LIB mstr_symbols
J 0
(975 2650);
PAINT ORANGE (975 2650);
DISPLAY INVISIBLE (975 2650);
FORCEPROP 0 LAST BOM_COST MEM
J 0
(975 2750);
PAINT ORANGE (975 2750);
DISPLAY INVISIBLE (975 2750);
FORCEPROP 1 LAST VOLTAGE 2.5V
J 0
(930 2607);
DISPLAY 0.340426 (930 2607);
PAINT SKYBLUE (930 2607);
DISPLAY INVISIBLE (930 2607);
FORCEADD SCONN288_H44441003..2
(1625 3950);
FORCEPROP 2 LASTPIN (2075 3550) $PN 255
J 0
(2085 3560);
DISPLAY 0.617021 (2085 3560);
PAINT ORANGE (2085 3560);
FORCEPROP 2 LASTPIN (2075 3600) $PN 256
J 0
(2085 3610);
DISPLAY 0.617021 (2085 3610);
PAINT ORANGE (2085 3610);
FORCEPROP 2 LASTPIN (2075 3450) $PN 244
J 0
(2085 3460);
DISPLAY 0.617021 (2085 3460);
PAINT ORANGE (2085 3460);
FORCEPROP 2 LASTPIN (2075 3400) $PN 186
J 0
(2085 3410);
DISPLAY 0.617021 (2085 3410);
PAINT ORANGE (2085 3410);
FORCEPROP 2 LASTPIN (2075 3050) $PN 152
J 0
(2085 3060);
DISPLAY 0.617021 (2085 3060);
PAINT ORANGE (2085 3060);
FORCEPROP 2 LASTPIN (2075 3100) $PN 153
J 0
(2085 3110);
DISPLAY 0.617021 (2085 3110);
PAINT ORANGE (2085 3110);
FORCEPROP 2 LASTPIN (2075 3150) $PN 163
J 0
(2085 3160);
DISPLAY 0.617021 (2085 3160);
PAINT ORANGE (2085 3160);
FORCEPROP 2 LASTPIN (2075 3200) $PN 164
J 0
(2085 3210);
DISPLAY 0.617021 (2085 3210);
PAINT ORANGE (2085 3210);
FORCEPROP 2 LASTPIN (2075 3250) $PN 174
J 0
(2085 3260);
DISPLAY 0.617021 (2085 3260);
PAINT ORANGE (2085 3260);
FORCEPROP 2 LASTPIN (2075 3300) $PN 175
J 0
(2085 3310);
DISPLAY 0.617021 (2085 3310);
PAINT ORANGE (2085 3310);
FORCEPROP 2 LASTPIN (2075 3350) $PN 185
J 0
(2085 3360);
DISPLAY 0.617021 (2085 3360);
PAINT ORANGE (2085 3360);
FORCEPROP 2 LASTPIN (2075 3500) $PN 245
J 0
(2085 3510);
DISPLAY 0.617021 (2085 3510);
PAINT ORANGE (2085 3510);
FORCEPROP 2 LASTPIN (2075 3650) $PN 266
J 0
(2085 3660);
DISPLAY 0.617021 (2085 3660);
PAINT ORANGE (2085 3660);
FORCEPROP 2 LASTPIN (2075 3700) $PN 267
J 0
(2085 3710);
DISPLAY 0.617021 (2085 3710);
PAINT ORANGE (2085 3710);
FORCEPROP 2 LASTPIN (2075 3750) $PN 277
J 0
(2085 3760);
DISPLAY 0.617021 (2085 3760);
PAINT ORANGE (2085 3760);
FORCEPROP 2 LASTPIN (2075 3800) $PN 278
J 0
(2085 3810);
DISPLAY 0.617021 (2085 3810);
PAINT ORANGE (2085 3810);
FORCEPROP 2 LASTPIN (2075 3850) $PN 196
J 0
(2085 3860);
DISPLAY 0.617021 (2085 3860);
PAINT ORANGE (2085 3860);
FORCEPROP 2 LASTPIN (2075 3900) $PN 197
J 0
(2085 3910);
DISPLAY 0.617021 (2085 3910);
PAINT ORANGE (2085 3910);
FORCEPROP 2 LASTPIN (2075 3950) $PN 8
J 0
(2085 3960);
DISPLAY 0.617021 (2085 3960);
PAINT ORANGE (2085 3960);
FORCEPROP 2 LASTPIN (2075 4000) $PN 7
J 0
(2085 4010);
DISPLAY 0.617021 (2085 4010);
PAINT ORANGE (2085 4010);
FORCEPROP 2 LASTPIN (2075 4050) $PN 19
J 0
(2085 4060);
DISPLAY 0.617021 (2085 4060);
PAINT ORANGE (2085 4060);
FORCEPROP 2 LASTPIN (2075 4150) $PN 30
J 0
(2085 4160);
DISPLAY 0.617021 (2085 4160);
PAINT ORANGE (2085 4160);
FORCEPROP 2 LASTPIN (2075 4200) $PN 29
J 0
(2085 4210);
DISPLAY 0.617021 (2085 4210);
PAINT ORANGE (2085 4210);
FORCEPROP 2 LASTPIN (2075 4250) $PN 41
J 0
(2085 4260);
DISPLAY 0.617021 (2085 4260);
PAINT ORANGE (2085 4260);
FORCEPROP 2 LASTPIN (2075 4300) $PN 40
J 0
(2085 4310);
DISPLAY 0.617021 (2085 4310);
PAINT ORANGE (2085 4310);
FORCEPROP 2 LASTPIN (2075 4350) $PN 100
J 0
(2085 4360);
DISPLAY 0.617021 (2085 4360);
PAINT ORANGE (2085 4360);
FORCEPROP 2 LASTPIN (2075 4400) $PN 99
J 0
(2085 4410);
DISPLAY 0.617021 (2085 4410);
PAINT ORANGE (2085 4410);
FORCEPROP 2 LASTPIN (2075 4450) $PN 111
J 0
(2085 4460);
DISPLAY 0.617021 (2085 4460);
PAINT ORANGE (2085 4460);
FORCEPROP 2 LASTPIN (2075 4500) $PN 110
J 0
(2085 4510);
DISPLAY 0.617021 (2085 4510);
PAINT ORANGE (2085 4510);
FORCEPROP 2 LASTPIN (2075 4550) $PN 122
J 0
(2085 4560);
DISPLAY 0.617021 (2085 4560);
PAINT ORANGE (2085 4560);
FORCEPROP 2 LASTPIN (2075 4600) $PN 121
J 0
(2085 4610);
DISPLAY 0.617021 (2085 4610);
PAINT ORANGE (2085 4610);
FORCEPROP 2 LASTPIN (2075 4650) $PN 133
J 0
(2085 4660);
DISPLAY 0.617021 (2085 4660);
PAINT ORANGE (2085 4660);
FORCEPROP 2 LASTPIN (2075 4700) $PN 132
J 0
(2085 4710);
DISPLAY 0.617021 (2085 4710);
PAINT ORANGE (2085 4710);
FORCEPROP 2 LASTPIN (2075 4750) $PN 52
J 0
(2085 4760);
DISPLAY 0.617021 (2085 4760);
PAINT ORANGE (2085 4760);
FORCEPROP 2 LASTPIN (2075 4800) $PN 51
J 0
(2085 4810);
DISPLAY 0.617021 (2085 4810);
PAINT ORANGE (2085 4810);
FORCEPROP 1 LAST MATERIAL SCONN
J 0
(1225 5000);
DISPLAY 0.617021 (1225 5000);
PAINT SKYBLUE (1225 5000);
FORCEPROP 1 LAST PART_NUMBER H44441-003
J 0
(1225 2850);
DISPLAY 0.617021 (1225 2850);
PAINT BLUE (1225 2850);
FORCEPROP 1 LAST LOCATION J6U1
J 0
(1225 5050);
DISPLAY 0.617021 (1225 5050);
PAINT AQUA (1225 5050);
FORCEPROP 2 LASTPIN (2075 4100) $PN 18
J 0
(2085 4110);
DISPLAY 0.617021 (2085 4110);
PAINT ORANGE (2085 4110);
FORCEPROP 0 LAST BOM_SS NOPOP
J 0
(1370 5021);
DISPLAY 1.021277 (1370 5021);
PAINT BROWN (1370 5021);
DISPLAY BOTH (1370 5021);
FORCEPROP 2 LAST ROOM DDR4_CH_B
J 0
(1225 5150);
PAINT ORANGE (1225 5150);
DISPLAY INVISIBLE (1225 5150);
FORCEPROP 1 LAST PATH I112
J 0
(1625 5000);
PAINT GREEN (1625 5000);
DISPLAY INVISIBLE (1625 5000);
FORCEPROP 2 LAST CDS_LOCATION J6U1
J 0
(1225 5050);
DISPLAY 0.617021 (1225 5050);
PAINT AQUA (1225 5050);
DISPLAY INVISIBLE (1225 5050);
FORCEPROP 2 LAST SEC 2
J 0
(1225 5100);
DISPLAY 0.680851 (1225 5100);
PAINT MONO (1225 5100);
DISPLAY INVISIBLE (1225 5100);
FORCEPROP 2 LAST SEC_TYPE PIP
J 0
(1225 5100);
DISPLAY 1.021277 (1225 5100);
PAINT ORANGE (1225 5100);
DISPLAY INVISIBLE (1225 5100);
FORCEPROP 2 LAST CDS_LIB mstr_sconn
J 0
(1625 3950);
PAINT ORANGE (1625 3950);
DISPLAY INVISIBLE (1625 3950);
FORCEPROP 2 LAST BOM_COST MEM
J 0
(1625 3950);
PAINT ORANGE (1625 3950);
DISPLAY INVISIBLE (1625 3950);
FORCEPROP 1 LAST PACK_TYPE PIP
J 0
(1225 5100);
PAINT SKYBLUE (1225 5100);
DISPLAY INVISIBLE (1225 5100);
FORCEADD OFFPAGE..1
(-2225 4300);
FORCEPROP 2 LAST $XR1 45 
J 0
(-2566 4300);
DISPLAY 0.638298 (-2566 4300);
PAINT MONO (-2566 4300);
FORCEPROP 2 LAST $XR0 24 
J 0
(-2476 4300);
DISPLAY 0.638298 (-2476 4300);
PAINT MONO (-2476 4300);
FORCEPROP 2 LAST PATH I113
J 0
(-2425 4350);
DISPLAY 1.021277 (-2425 4350);
PAINT ORANGE (-2425 4350);
DISPLAY INVISIBLE (-2425 4350);
FORCEPROP 1 LAST COMMENT_BODY TRUE
J 0
(-2100 4200);
DISPLAY 0.936170 (-2100 4200);
PAINT GREEN (-2100 4200);
DISPLAY INVISIBLE (-2100 4200);
FORCEPROP 1 LAST OFFPAGE TRUE
J 0
(-1900 4175);
DISPLAY 0.936170 (-1900 4175);
PAINT GREEN (-1900 4175);
DISPLAY INVISIBLE (-1900 4175);
FORCEPROP 2 LAST CDS_LIB mstr_standard
J 0
(-2225 4300);
DISPLAY 0.787234 (-2225 4300);
PAINT MONO (-2225 4300);
DISPLAY INVISIBLE (-2225 4300);
FORCEADD TAP..6
(-1575 3750);
FORCEPROP 3 LASTPIN (-1525 3750) SIG_NAME M_B_MA<7>
J 0
(-1515 3760);
DISPLAY 0.659574 (-1515 3760);
PAINT MONO (-1515 3760);
DISPLAY INVISIBLE (-1515 3760);
FORCEPROP 1 LASTPIN (-1525 3750) BN 7
J 0
(-1575 3760);
DISPLAY 0.617021 (-1575 3760);
PAINT PINK (-1575 3760);
FORCEPROP 1 LAST PATH I114
J 0
(-1577 3750);
DISPLAY 0.872340 (-1577 3750);
PAINT GREEN (-1577 3750);
DISPLAY INVISIBLE (-1577 3750);
FORCEPROP 1 LAST HDL_TAP TRUE
J 0
(-1250 3625);
DISPLAY 1.234043 (-1250 3625);
PAINT GREEN (-1250 3625);
DISPLAY INVISIBLE (-1250 3625);
FORCEPROP 1 LAST BODY_TYPE PLUMBING
J 0
(-1575 3700);
DISPLAY 1.234043 (-1575 3700);
PAINT GREEN (-1575 3700);
DISPLAY INVISIBLE (-1575 3700);
FORCEPROP 2 LAST CDS_LIB mstr_standard
J 2
(-1575 3750);
DISPLAY 0.787234 (-1575 3750);
PAINT MONO (-1575 3750);
DISPLAY INVISIBLE (-1575 3750);
FORCEADD TAP..6
(-1575 3800);
FORCEPROP 3 LASTPIN (-1525 3800) SIG_NAME M_B_MA<8>
J 0
(-1515 3810);
DISPLAY 0.659574 (-1515 3810);
PAINT MONO (-1515 3810);
DISPLAY INVISIBLE (-1515 3810);
FORCEPROP 1 LASTPIN (-1525 3800) BN 8
J 0
(-1575 3810);
DISPLAY 0.617021 (-1575 3810);
PAINT PINK (-1575 3810);
FORCEPROP 1 LAST PATH I115
J 0
(-1577 3800);
DISPLAY 0.872340 (-1577 3800);
PAINT GREEN (-1577 3800);
DISPLAY INVISIBLE (-1577 3800);
FORCEPROP 1 LAST HDL_TAP TRUE
J 0
(-1250 3675);
DISPLAY 1.234043 (-1250 3675);
PAINT GREEN (-1250 3675);
DISPLAY INVISIBLE (-1250 3675);
FORCEPROP 1 LAST BODY_TYPE PLUMBING
J 0
(-1575 3750);
DISPLAY 1.234043 (-1575 3750);
PAINT GREEN (-1575 3750);
DISPLAY INVISIBLE (-1575 3750);
FORCEPROP 2 LAST CDS_LIB mstr_standard
J 2
(-1575 3800);
DISPLAY 0.787234 (-1575 3800);
PAINT MONO (-1575 3800);
DISPLAY INVISIBLE (-1575 3800);
FORCEADD TAP..6
(-1575 3950);
FORCEPROP 3 LASTPIN (-1525 3950) SIG_NAME M_B_MA<11>
J 0
(-1515 3960);
DISPLAY 0.659574 (-1515 3960);
PAINT MONO (-1515 3960);
DISPLAY INVISIBLE (-1515 3960);
FORCEPROP 1 LASTPIN (-1525 3950) BN 11
J 0
(-1575 3960);
DISPLAY 0.617021 (-1575 3960);
PAINT PINK (-1575 3960);
FORCEPROP 1 LAST PATH I116
J 0
(-1577 3950);
DISPLAY 0.872340 (-1577 3950);
PAINT GREEN (-1577 3950);
DISPLAY INVISIBLE (-1577 3950);
FORCEPROP 1 LAST HDL_TAP TRUE
J 0
(-1250 3825);
DISPLAY 1.234043 (-1250 3825);
PAINT GREEN (-1250 3825);
DISPLAY INVISIBLE (-1250 3825);
FORCEPROP 1 LAST BODY_TYPE PLUMBING
J 0
(-1575 3900);
DISPLAY 1.234043 (-1575 3900);
PAINT GREEN (-1575 3900);
DISPLAY INVISIBLE (-1575 3900);
FORCEPROP 2 LAST CDS_LIB mstr_standard
J 2
(-1575 3950);
DISPLAY 0.787234 (-1575 3950);
PAINT MONO (-1575 3950);
DISPLAY INVISIBLE (-1575 3950);
FORCEADD TAP..6
(-1575 3900);
FORCEPROP 3 LASTPIN (-1525 3900) SIG_NAME M_B_MA<10>
J 0
(-1515 3910);
DISPLAY 0.659574 (-1515 3910);
PAINT MONO (-1515 3910);
DISPLAY INVISIBLE (-1515 3910);
FORCEPROP 1 LASTPIN (-1525 3900) BN 10
J 0
(-1575 3910);
DISPLAY 0.617021 (-1575 3910);
PAINT PINK (-1575 3910);
FORCEPROP 1 LAST PATH I117
J 0
(-1577 3900);
DISPLAY 0.872340 (-1577 3900);
PAINT GREEN (-1577 3900);
DISPLAY INVISIBLE (-1577 3900);
FORCEPROP 1 LAST HDL_TAP TRUE
J 0
(-1250 3775);
DISPLAY 1.234043 (-1250 3775);
PAINT GREEN (-1250 3775);
DISPLAY INVISIBLE (-1250 3775);
FORCEPROP 1 LAST BODY_TYPE PLUMBING
J 0
(-1575 3850);
DISPLAY 1.234043 (-1575 3850);
PAINT GREEN (-1575 3850);
DISPLAY INVISIBLE (-1575 3850);
FORCEPROP 2 LAST CDS_LIB mstr_standard
J 2
(-1575 3900);
DISPLAY 0.787234 (-1575 3900);
PAINT MONO (-1575 3900);
DISPLAY INVISIBLE (-1575 3900);
FORCEADD TAP..6
(-1575 3850);
FORCEPROP 3 LASTPIN (-1525 3850) SIG_NAME M_B_MA<9>
J 0
(-1515 3860);
DISPLAY 0.659574 (-1515 3860);
PAINT MONO (-1515 3860);
DISPLAY INVISIBLE (-1515 3860);
FORCEPROP 1 LASTPIN (-1525 3850) BN 9
J 0
(-1575 3860);
DISPLAY 0.617021 (-1575 3860);
PAINT PINK (-1575 3860);
FORCEPROP 1 LAST PATH I118
J 0
(-1577 3850);
DISPLAY 0.872340 (-1577 3850);
PAINT GREEN (-1577 3850);
DISPLAY INVISIBLE (-1577 3850);
FORCEPROP 1 LAST HDL_TAP TRUE
J 0
(-1250 3725);
DISPLAY 1.234043 (-1250 3725);
PAINT GREEN (-1250 3725);
DISPLAY INVISIBLE (-1250 3725);
FORCEPROP 1 LAST BODY_TYPE PLUMBING
J 0
(-1575 3800);
DISPLAY 1.234043 (-1575 3800);
PAINT GREEN (-1575 3800);
DISPLAY INVISIBLE (-1575 3800);
FORCEPROP 2 LAST CDS_LIB mstr_standard
J 2
(-1575 3850);
DISPLAY 0.787234 (-1575 3850);
PAINT MONO (-1575 3850);
DISPLAY INVISIBLE (-1575 3850);
FORCEADD TAP..6
(-1575 4000);
FORCEPROP 3 LASTPIN (-1525 4000) SIG_NAME M_B_MA<12>
J 0
(-1515 4010);
DISPLAY 0.659574 (-1515 4010);
PAINT MONO (-1515 4010);
DISPLAY INVISIBLE (-1515 4010);
FORCEPROP 1 LASTPIN (-1525 4000) BN 12
J 0
(-1575 4010);
DISPLAY 0.617021 (-1575 4010);
PAINT PINK (-1575 4010);
FORCEPROP 1 LAST PATH I119
J 0
(-1577 4000);
DISPLAY 0.872340 (-1577 4000);
PAINT GREEN (-1577 4000);
DISPLAY INVISIBLE (-1577 4000);
FORCEPROP 1 LAST HDL_TAP TRUE
J 0
(-1250 3875);
DISPLAY 1.234043 (-1250 3875);
PAINT GREEN (-1250 3875);
DISPLAY INVISIBLE (-1250 3875);
FORCEPROP 1 LAST BODY_TYPE PLUMBING
J 0
(-1575 3950);
DISPLAY 1.234043 (-1575 3950);
PAINT GREEN (-1575 3950);
DISPLAY INVISIBLE (-1575 3950);
FORCEPROP 2 LAST CDS_LIB mstr_standard
J 2
(-1575 4000);
DISPLAY 0.787234 (-1575 4000);
PAINT MONO (-1575 4000);
DISPLAY INVISIBLE (-1575 4000);
FORCEADD OFFPAGE..1
(-2225 1200);
FORCEPROP 2 LAST $XR5 48 
J 0
(-2926 1200);
DISPLAY 0.638298 (-2926 1200);
PAINT MONO (-2926 1200);
FORCEPROP 2 LAST $XR4 47 
J 0
(-2836 1200);
DISPLAY 0.638298 (-2836 1200);
PAINT MONO (-2836 1200);
FORCEPROP 2 LAST $XR3 45 
J 0
(-2746 1200);
DISPLAY 0.638298 (-2746 1200);
PAINT MONO (-2746 1200);
FORCEPROP 2 LAST $XR2 44 
J 0
(-2656 1200);
DISPLAY 0.638298 (-2656 1200);
PAINT MONO (-2656 1200);
FORCEPROP 2 LAST $XR1 43 
J 0
(-2566 1200);
DISPLAY 0.638298 (-2566 1200);
PAINT MONO (-2566 1200);
FORCEPROP 2 LAST $XR0 99 
J 0
(-2476 1200);
DISPLAY 0.638298 (-2476 1200);
PAINT MONO (-2476 1200);
FORCEPROP 2 LAST PATH I12
J 0
(-2475 1250);
DISPLAY 1.021277 (-2475 1250);
PAINT ORANGE (-2475 1250);
DISPLAY INVISIBLE (-2475 1250);
FORCEPROP 1 LAST COMMENT_BODY TRUE
J 0
(-2100 1100);
DISPLAY 0.936170 (-2100 1100);
PAINT GREEN (-2100 1100);
DISPLAY INVISIBLE (-2100 1100);
FORCEPROP 1 LAST OFFPAGE TRUE
J 0
(-1900 1075);
DISPLAY 0.936170 (-1900 1075);
PAINT GREEN (-1900 1075);
DISPLAY INVISIBLE (-1900 1075);
FORCEPROP 2 LAST CDS_LIB mstr_standard
J 0
(-2225 1200);
DISPLAY 0.787234 (-2225 1200);
PAINT MONO (-2225 1200);
DISPLAY INVISIBLE (-2225 1200);
FORCEADD TAP..6
(-1575 4050);
FORCEPROP 3 LASTPIN (-1525 4050) SIG_NAME M_B_MA<13>
J 0
(-1515 4060);
DISPLAY 0.659574 (-1515 4060);
PAINT MONO (-1515 4060);
DISPLAY INVISIBLE (-1515 4060);
FORCEPROP 1 LASTPIN (-1525 4050) BN 13
J 0
(-1575 4060);
DISPLAY 0.617021 (-1575 4060);
PAINT PINK (-1575 4060);
FORCEPROP 1 LAST PATH I120
J 0
(-1577 4050);
DISPLAY 0.872340 (-1577 4050);
PAINT GREEN (-1577 4050);
DISPLAY INVISIBLE (-1577 4050);
FORCEPROP 1 LAST HDL_TAP TRUE
J 0
(-1250 3925);
DISPLAY 1.234043 (-1250 3925);
PAINT GREEN (-1250 3925);
DISPLAY INVISIBLE (-1250 3925);
FORCEPROP 1 LAST BODY_TYPE PLUMBING
J 0
(-1575 4000);
DISPLAY 1.234043 (-1575 4000);
PAINT GREEN (-1575 4000);
DISPLAY INVISIBLE (-1575 4000);
FORCEPROP 2 LAST CDS_LIB mstr_standard
J 2
(-1575 4050);
DISPLAY 0.787234 (-1575 4050);
PAINT MONO (-1575 4050);
DISPLAY INVISIBLE (-1575 4050);
FORCEADD TAP..6
(-1575 4100);
FORCEPROP 3 LASTPIN (-1525 4100) SIG_NAME M_B_MA<14>
J 0
(-1515 4110);
DISPLAY 0.659574 (-1515 4110);
PAINT MONO (-1515 4110);
DISPLAY INVISIBLE (-1515 4110);
FORCEPROP 1 LASTPIN (-1525 4100) BN 14
J 0
(-1575 4110);
DISPLAY 0.617021 (-1575 4110);
PAINT PINK (-1575 4110);
FORCEPROP 1 LAST PATH I121
J 0
(-1577 4100);
DISPLAY 0.872340 (-1577 4100);
PAINT GREEN (-1577 4100);
DISPLAY INVISIBLE (-1577 4100);
FORCEPROP 1 LAST HDL_TAP TRUE
J 0
(-1250 3975);
DISPLAY 1.234043 (-1250 3975);
PAINT GREEN (-1250 3975);
DISPLAY INVISIBLE (-1250 3975);
FORCEPROP 1 LAST BODY_TYPE PLUMBING
J 0
(-1575 4050);
DISPLAY 1.234043 (-1575 4050);
PAINT GREEN (-1575 4050);
DISPLAY INVISIBLE (-1575 4050);
FORCEPROP 2 LAST CDS_LIB mstr_standard
J 2
(-1575 4100);
DISPLAY 0.787234 (-1575 4100);
PAINT MONO (-1575 4100);
DISPLAY INVISIBLE (-1575 4100);
FORCEADD TAP..6
(-1575 4200);
FORCEPROP 3 LASTPIN (-1525 4200) SIG_NAME M_B_MA<16>
J 0
(-1515 4210);
DISPLAY 0.659574 (-1515 4210);
PAINT MONO (-1515 4210);
DISPLAY INVISIBLE (-1515 4210);
FORCEPROP 1 LASTPIN (-1525 4200) BN 16
J 0
(-1575 4210);
DISPLAY 0.617021 (-1575 4210);
PAINT PINK (-1575 4210);
FORCEPROP 1 LAST PATH I122
J 0
(-1577 4200);
DISPLAY 0.872340 (-1577 4200);
PAINT GREEN (-1577 4200);
DISPLAY INVISIBLE (-1577 4200);
FORCEPROP 1 LAST HDL_TAP TRUE
J 0
(-1250 4075);
DISPLAY 1.234043 (-1250 4075);
PAINT GREEN (-1250 4075);
DISPLAY INVISIBLE (-1250 4075);
FORCEPROP 1 LAST BODY_TYPE PLUMBING
J 0
(-1575 4150);
DISPLAY 1.234043 (-1575 4150);
PAINT GREEN (-1575 4150);
DISPLAY INVISIBLE (-1575 4150);
FORCEPROP 2 LAST CDS_LIB mstr_standard
J 2
(-1575 4200);
DISPLAY 0.787234 (-1575 4200);
PAINT MONO (-1575 4200);
DISPLAY INVISIBLE (-1575 4200);
FORCEADD TAP..6
(-1575 4150);
FORCEPROP 3 LASTPIN (-1525 4150) SIG_NAME M_B_MA<15>
J 0
(-1515 4160);
DISPLAY 0.659574 (-1515 4160);
PAINT MONO (-1515 4160);
DISPLAY INVISIBLE (-1515 4160);
FORCEPROP 1 LASTPIN (-1525 4150) BN 15
J 0
(-1575 4160);
DISPLAY 0.617021 (-1575 4160);
PAINT PINK (-1575 4160);
FORCEPROP 1 LAST PATH I123
J 0
(-1577 4150);
DISPLAY 0.872340 (-1577 4150);
PAINT GREEN (-1577 4150);
DISPLAY INVISIBLE (-1577 4150);
FORCEPROP 1 LAST HDL_TAP TRUE
J 0
(-1250 4025);
DISPLAY 1.234043 (-1250 4025);
PAINT GREEN (-1250 4025);
DISPLAY INVISIBLE (-1250 4025);
FORCEPROP 1 LAST BODY_TYPE PLUMBING
J 0
(-1575 4100);
DISPLAY 1.234043 (-1575 4100);
PAINT GREEN (-1575 4100);
DISPLAY INVISIBLE (-1575 4100);
FORCEPROP 2 LAST CDS_LIB mstr_standard
J 2
(-1575 4150);
DISPLAY 0.787234 (-1575 4150);
PAINT MONO (-1575 4150);
DISPLAY INVISIBLE (-1575 4150);
FORCEADD TAP..6
(-1575 4250);
FORCEPROP 3 LASTPIN (-1525 4250) SIG_NAME M_B_MA<17>
J 0
(-1515 4260);
DISPLAY 0.659574 (-1515 4260);
PAINT MONO (-1515 4260);
DISPLAY INVISIBLE (-1515 4260);
FORCEPROP 1 LASTPIN (-1525 4250) BN 17
J 0
(-1575 4260);
DISPLAY 0.617021 (-1575 4260);
PAINT PINK (-1575 4260);
FORCEPROP 1 LAST PATH I124
J 0
(-1577 4250);
DISPLAY 0.872340 (-1577 4250);
PAINT GREEN (-1577 4250);
DISPLAY INVISIBLE (-1577 4250);
FORCEPROP 1 LAST HDL_TAP TRUE
J 0
(-1250 4125);
DISPLAY 1.234043 (-1250 4125);
PAINT GREEN (-1250 4125);
DISPLAY INVISIBLE (-1250 4125);
FORCEPROP 1 LAST BODY_TYPE PLUMBING
J 0
(-1575 4200);
DISPLAY 1.234043 (-1575 4200);
PAINT GREEN (-1575 4200);
DISPLAY INVISIBLE (-1575 4200);
FORCEPROP 2 LAST CDS_LIB mstr_standard
J 0
(-1575 4250);
DISPLAY 0.787234 (-1575 4250);
PAINT MONO (-1575 4250);
DISPLAY INVISIBLE (-1575 4250);
FORCEADD TAP..6
R 2
(-75 3750);
FORCEPROP 3 LASTPIN (-125 3750) SIG_NAME M_B_DQ<53>
J 0
(-115 3760);
DISPLAY 0.659574 (-115 3760);
PAINT MONO (-115 3760);
DISPLAY INVISIBLE (-115 3760);
FORCEPROP 1 LASTPIN (-125 3750) BN 53
J 2
(-75 3760);
DISPLAY 0.617021 (-75 3760);
PAINT PINK (-75 3760);
FORCEPROP 1 LAST PATH I125
J 2
(-73 3750);
DISPLAY 0.872340 (-73 3750);
PAINT GREEN (-73 3750);
DISPLAY INVISIBLE (-73 3750);
FORCEPROP 1 LAST HDL_TAP TRUE
J 2
(-400 3625);
DISPLAY 1.234043 (-400 3625);
PAINT GREEN (-400 3625);
DISPLAY INVISIBLE (-400 3625);
FORCEPROP 1 LAST BODY_TYPE PLUMBING
J 2
(-75 3700);
DISPLAY 1.234043 (-75 3700);
PAINT GREEN (-75 3700);
DISPLAY INVISIBLE (-75 3700);
FORCEPROP 2 LAST CDS_LIB mstr_standard
J 2
(-75 3750);
DISPLAY 0.787234 (-75 3750);
PAINT MONO (-75 3750);
DISPLAY INVISIBLE (-75 3750);
FORCEADD TAP..6
R 2
(-75 3850);
FORCEPROP 3 LASTPIN (-125 3850) SIG_NAME M_B_DQ<55>
J 0
(-115 3860);
DISPLAY 0.659574 (-115 3860);
PAINT MONO (-115 3860);
DISPLAY INVISIBLE (-115 3860);
FORCEPROP 1 LASTPIN (-125 3850) BN 55
J 2
(-75 3860);
DISPLAY 0.617021 (-75 3860);
PAINT PINK (-75 3860);
FORCEPROP 1 LAST PATH I126
J 2
(-73 3850);
DISPLAY 0.872340 (-73 3850);
PAINT GREEN (-73 3850);
DISPLAY INVISIBLE (-73 3850);
FORCEPROP 1 LAST HDL_TAP TRUE
J 2
(-400 3725);
DISPLAY 1.234043 (-400 3725);
PAINT GREEN (-400 3725);
DISPLAY INVISIBLE (-400 3725);
FORCEPROP 1 LAST BODY_TYPE PLUMBING
J 2
(-75 3800);
DISPLAY 1.234043 (-75 3800);
PAINT GREEN (-75 3800);
DISPLAY INVISIBLE (-75 3800);
FORCEPROP 2 LAST CDS_LIB mstr_standard
J 2
(-75 3850);
DISPLAY 0.787234 (-75 3850);
PAINT MONO (-75 3850);
DISPLAY INVISIBLE (-75 3850);
FORCEADD TAP..6
R 2
(-75 3800);
FORCEPROP 3 LASTPIN (-125 3800) SIG_NAME M_B_DQ<54>
J 0
(-115 3810);
DISPLAY 0.659574 (-115 3810);
PAINT MONO (-115 3810);
DISPLAY INVISIBLE (-115 3810);
FORCEPROP 1 LASTPIN (-125 3800) BN 54
J 2
(-75 3810);
DISPLAY 0.617021 (-75 3810);
PAINT PINK (-75 3810);
FORCEPROP 1 LAST PATH I127
J 2
(-73 3800);
DISPLAY 0.872340 (-73 3800);
PAINT GREEN (-73 3800);
DISPLAY INVISIBLE (-73 3800);
FORCEPROP 1 LAST HDL_TAP TRUE
J 2
(-400 3675);
DISPLAY 1.234043 (-400 3675);
PAINT GREEN (-400 3675);
DISPLAY INVISIBLE (-400 3675);
FORCEPROP 1 LAST BODY_TYPE PLUMBING
J 2
(-75 3750);
DISPLAY 1.234043 (-75 3750);
PAINT GREEN (-75 3750);
DISPLAY INVISIBLE (-75 3750);
FORCEPROP 2 LAST CDS_LIB mstr_standard
J 2
(-75 3800);
DISPLAY 0.787234 (-75 3800);
PAINT MONO (-75 3800);
DISPLAY INVISIBLE (-75 3800);
FORCEADD TAP..6
R 2
(-75 3950);
FORCEPROP 3 LASTPIN (-125 3950) SIG_NAME M_B_DQ<57>
J 0
(-115 3960);
DISPLAY 0.659574 (-115 3960);
PAINT MONO (-115 3960);
DISPLAY INVISIBLE (-115 3960);
FORCEPROP 1 LASTPIN (-125 3950) BN 57
J 2
(-75 3960);
DISPLAY 0.617021 (-75 3960);
PAINT PINK (-75 3960);
FORCEPROP 1 LAST PATH I128
J 2
(-73 3950);
DISPLAY 0.872340 (-73 3950);
PAINT GREEN (-73 3950);
DISPLAY INVISIBLE (-73 3950);
FORCEPROP 1 LAST HDL_TAP TRUE
J 2
(-400 3825);
DISPLAY 1.234043 (-400 3825);
PAINT GREEN (-400 3825);
DISPLAY INVISIBLE (-400 3825);
FORCEPROP 1 LAST BODY_TYPE PLUMBING
J 2
(-75 3900);
DISPLAY 1.234043 (-75 3900);
PAINT GREEN (-75 3900);
DISPLAY INVISIBLE (-75 3900);
FORCEPROP 2 LAST CDS_LIB mstr_standard
J 2
(-75 3950);
DISPLAY 0.787234 (-75 3950);
PAINT MONO (-75 3950);
DISPLAY INVISIBLE (-75 3950);
FORCEADD TAP..6
R 2
(-75 3900);
FORCEPROP 3 LASTPIN (-125 3900) SIG_NAME M_B_DQ<56>
J 0
(-115 3910);
DISPLAY 0.659574 (-115 3910);
PAINT MONO (-115 3910);
DISPLAY INVISIBLE (-115 3910);
FORCEPROP 1 LASTPIN (-125 3900) BN 56
J 2
(-75 3910);
DISPLAY 0.617021 (-75 3910);
PAINT PINK (-75 3910);
FORCEPROP 1 LAST PATH I129
J 2
(-73 3900);
DISPLAY 0.872340 (-73 3900);
PAINT GREEN (-73 3900);
DISPLAY INVISIBLE (-73 3900);
FORCEPROP 1 LAST HDL_TAP TRUE
J 2
(-400 3775);
DISPLAY 1.234043 (-400 3775);
PAINT GREEN (-400 3775);
DISPLAY INVISIBLE (-400 3775);
FORCEPROP 1 LAST BODY_TYPE PLUMBING
J 2
(-75 3850);
DISPLAY 1.234043 (-75 3850);
PAINT GREEN (-75 3850);
DISPLAY INVISIBLE (-75 3850);
FORCEPROP 2 LAST CDS_LIB mstr_standard
J 2
(-75 3900);
DISPLAY 0.787234 (-75 3900);
PAINT MONO (-75 3900);
DISPLAY INVISIBLE (-75 3900);
FORCEADD OFFPAGE..6
(-2225 1250);
FORCEPROP 2 LASTPIN (-2175 1250) SIG_NAME SMB_DDR_ABC_VPP_SDA
J 0
(-2135 1260);
DISPLAY 0.617021 (-2135 1260);
PAINT ORANGE (-2135 1260);
FORCEPROP 2 LAST $XR5 99 
J 0
(-2924 1250);
DISPLAY 0.638298 (-2924 1250);
PAINT MONO (-2924 1250);
FORCEPROP 2 LAST $XR4 48 
J 0
(-2834 1250);
DISPLAY 0.638298 (-2834 1250);
PAINT MONO (-2834 1250);
FORCEPROP 2 LAST $XR3 47 
J 0
(-2744 1250);
DISPLAY 0.638298 (-2744 1250);
PAINT MONO (-2744 1250);
FORCEPROP 2 LAST $XR2 45 
J 0
(-2654 1250);
DISPLAY 0.638298 (-2654 1250);
PAINT MONO (-2654 1250);
FORCEPROP 2 LAST $XR1 44 
J 0
(-2564 1250);
DISPLAY 0.638298 (-2564 1250);
PAINT MONO (-2564 1250);
FORCEPROP 2 LAST $XR0 43 
J 0
(-2474 1250);
DISPLAY 0.638298 (-2474 1250);
PAINT MONO (-2474 1250);
FORCEPROP 2 LAST PATH I13
J 0
(-2450 1300);
DISPLAY 1.021277 (-2450 1300);
PAINT ORANGE (-2450 1300);
DISPLAY INVISIBLE (-2450 1300);
FORCEPROP 1 LAST COMMENT_BODY TRUE
J 0
(-2125 1175);
DISPLAY 0.936170 (-2125 1175);
PAINT GREEN (-2125 1175);
DISPLAY INVISIBLE (-2125 1175);
FORCEPROP 1 LAST OFFPAGE TRUE
J 0
(-1900 1125);
DISPLAY 0.936170 (-1900 1125);
PAINT GREEN (-1900 1125);
DISPLAY INVISIBLE (-1900 1125);
FORCEPROP 2 LAST CDS_LIB mstr_standard
J 0
(-2225 1250);
DISPLAY 0.787234 (-2225 1250);
PAINT MONO (-2225 1250);
DISPLAY INVISIBLE (-2225 1250);
FORCEADD TAP..6
R 2
(-75 4000);
FORCEPROP 3 LASTPIN (-125 4000) SIG_NAME M_B_DQ<58>
J 0
(-115 4010);
DISPLAY 0.659574 (-115 4010);
PAINT MONO (-115 4010);
DISPLAY INVISIBLE (-115 4010);
FORCEPROP 1 LASTPIN (-125 4000) BN 58
J 2
(-75 4010);
DISPLAY 0.617021 (-75 4010);
PAINT PINK (-75 4010);
FORCEPROP 1 LAST PATH I130
J 2
(-73 4000);
DISPLAY 0.872340 (-73 4000);
PAINT GREEN (-73 4000);
DISPLAY INVISIBLE (-73 4000);
FORCEPROP 1 LAST HDL_TAP TRUE
J 2
(-400 3875);
DISPLAY 1.234043 (-400 3875);
PAINT GREEN (-400 3875);
DISPLAY INVISIBLE (-400 3875);
FORCEPROP 1 LAST BODY_TYPE PLUMBING
J 2
(-75 3950);
DISPLAY 1.234043 (-75 3950);
PAINT GREEN (-75 3950);
DISPLAY INVISIBLE (-75 3950);
FORCEPROP 2 LAST CDS_LIB mstr_standard
J 2
(-75 4000);
DISPLAY 0.787234 (-75 4000);
PAINT MONO (-75 4000);
DISPLAY INVISIBLE (-75 4000);
FORCEADD TAP..6
R 2
(-75 4050);
FORCEPROP 3 LASTPIN (-125 4050) SIG_NAME M_B_DQ<59>
J 0
(-115 4060);
DISPLAY 0.659574 (-115 4060);
PAINT MONO (-115 4060);
DISPLAY INVISIBLE (-115 4060);
FORCEPROP 1 LASTPIN (-125 4050) BN 59
J 2
(-75 4060);
DISPLAY 0.617021 (-75 4060);
PAINT PINK (-75 4060);
FORCEPROP 1 LAST PATH I131
J 2
(-73 4050);
DISPLAY 0.872340 (-73 4050);
PAINT GREEN (-73 4050);
DISPLAY INVISIBLE (-73 4050);
FORCEPROP 1 LAST HDL_TAP TRUE
J 2
(-400 3925);
DISPLAY 1.234043 (-400 3925);
PAINT GREEN (-400 3925);
DISPLAY INVISIBLE (-400 3925);
FORCEPROP 1 LAST BODY_TYPE PLUMBING
J 2
(-75 4000);
DISPLAY 1.234043 (-75 4000);
PAINT GREEN (-75 4000);
DISPLAY INVISIBLE (-75 4000);
FORCEPROP 2 LAST CDS_LIB mstr_standard
J 2
(-75 4050);
DISPLAY 0.787234 (-75 4050);
PAINT MONO (-75 4050);
DISPLAY INVISIBLE (-75 4050);
FORCEADD TAP..6
R 2
(-75 4100);
FORCEPROP 3 LASTPIN (-125 4100) SIG_NAME M_B_DQ<60>
J 0
(-115 4110);
DISPLAY 0.659574 (-115 4110);
PAINT MONO (-115 4110);
DISPLAY INVISIBLE (-115 4110);
FORCEPROP 1 LASTPIN (-125 4100) BN 60
J 2
(-75 4110);
DISPLAY 0.617021 (-75 4110);
PAINT PINK (-75 4110);
FORCEPROP 1 LAST PATH I132
J 2
(-73 4100);
DISPLAY 0.872340 (-73 4100);
PAINT GREEN (-73 4100);
DISPLAY INVISIBLE (-73 4100);
FORCEPROP 1 LAST HDL_TAP TRUE
J 2
(-400 3975);
DISPLAY 1.234043 (-400 3975);
PAINT GREEN (-400 3975);
DISPLAY INVISIBLE (-400 3975);
FORCEPROP 1 LAST BODY_TYPE PLUMBING
J 2
(-75 4050);
DISPLAY 1.234043 (-75 4050);
PAINT GREEN (-75 4050);
DISPLAY INVISIBLE (-75 4050);
FORCEPROP 2 LAST CDS_LIB mstr_standard
J 2
(-75 4100);
DISPLAY 0.787234 (-75 4100);
PAINT MONO (-75 4100);
DISPLAY INVISIBLE (-75 4100);
FORCEADD TAP..6
R 2
(-75 4150);
FORCEPROP 3 LASTPIN (-125 4150) SIG_NAME M_B_DQ<61>
J 0
(-115 4160);
DISPLAY 0.659574 (-115 4160);
PAINT MONO (-115 4160);
DISPLAY INVISIBLE (-115 4160);
FORCEPROP 1 LASTPIN (-125 4150) BN 61
J 2
(-75 4160);
DISPLAY 0.617021 (-75 4160);
PAINT PINK (-75 4160);
FORCEPROP 1 LAST PATH I133
J 2
(-73 4150);
DISPLAY 0.872340 (-73 4150);
PAINT GREEN (-73 4150);
DISPLAY INVISIBLE (-73 4150);
FORCEPROP 1 LAST HDL_TAP TRUE
J 2
(-400 4025);
DISPLAY 1.234043 (-400 4025);
PAINT GREEN (-400 4025);
DISPLAY INVISIBLE (-400 4025);
FORCEPROP 1 LAST BODY_TYPE PLUMBING
J 2
(-75 4100);
DISPLAY 1.234043 (-75 4100);
PAINT GREEN (-75 4100);
DISPLAY INVISIBLE (-75 4100);
FORCEPROP 2 LAST CDS_LIB mstr_standard
J 2
(-75 4150);
DISPLAY 0.787234 (-75 4150);
PAINT MONO (-75 4150);
DISPLAY INVISIBLE (-75 4150);
FORCEADD TAP..6
R 2
(-75 4200);
FORCEPROP 3 LASTPIN (-125 4200) SIG_NAME M_B_DQ<62>
J 0
(-115 4210);
DISPLAY 0.659574 (-115 4210);
PAINT MONO (-115 4210);
DISPLAY INVISIBLE (-115 4210);
FORCEPROP 1 LASTPIN (-125 4200) BN 62
J 2
(-75 4210);
DISPLAY 0.617021 (-75 4210);
PAINT PINK (-75 4210);
FORCEPROP 1 LAST PATH I134
J 2
(-73 4200);
DISPLAY 0.872340 (-73 4200);
PAINT GREEN (-73 4200);
DISPLAY INVISIBLE (-73 4200);
FORCEPROP 1 LAST HDL_TAP TRUE
J 2
(-400 4075);
DISPLAY 1.234043 (-400 4075);
PAINT GREEN (-400 4075);
DISPLAY INVISIBLE (-400 4075);
FORCEPROP 1 LAST BODY_TYPE PLUMBING
J 2
(-75 4150);
DISPLAY 1.234043 (-75 4150);
PAINT GREEN (-75 4150);
DISPLAY INVISIBLE (-75 4150);
FORCEPROP 2 LAST CDS_LIB mstr_standard
J 2
(-75 4200);
DISPLAY 0.787234 (-75 4200);
PAINT MONO (-75 4200);
DISPLAY INVISIBLE (-75 4200);
FORCEADD TAP..6
R 2
(-75 4250);
FORCEPROP 3 LASTPIN (-125 4250) SIG_NAME M_B_DQ<63>
J 0
(-115 4260);
DISPLAY 0.659574 (-115 4260);
PAINT MONO (-115 4260);
DISPLAY INVISIBLE (-115 4260);
FORCEPROP 1 LASTPIN (-125 4250) BN 63
J 2
(-75 4260);
DISPLAY 0.617021 (-75 4260);
PAINT PINK (-75 4260);
FORCEPROP 1 LAST PATH I135
J 2
(-73 4250);
DISPLAY 0.872340 (-73 4250);
PAINT GREEN (-73 4250);
DISPLAY INVISIBLE (-73 4250);
FORCEPROP 1 LAST HDL_TAP TRUE
J 2
(-400 4125);
DISPLAY 1.234043 (-400 4125);
PAINT GREEN (-400 4125);
DISPLAY INVISIBLE (-400 4125);
FORCEPROP 1 LAST BODY_TYPE PLUMBING
J 2
(-75 4200);
DISPLAY 1.234043 (-75 4200);
PAINT GREEN (-75 4200);
DISPLAY INVISIBLE (-75 4200);
FORCEPROP 2 LAST CDS_LIB mstr_standard
J 2
(-75 4250);
DISPLAY 0.787234 (-75 4250);
PAINT MONO (-75 4250);
DISPLAY INVISIBLE (-75 4250);
FORCEADD OFFPAGE..3
(475 4300);
FORCEPROP 2 LAST $XR1 45 
J 0
(779 4300);
DISPLAY 0.638298 (779 4300);
PAINT MONO (779 4300);
FORCEPROP 2 LAST $XR0 24 
J 0
(689 4300);
DISPLAY 0.638298 (689 4300);
PAINT MONO (689 4300);
FORCEPROP 2 LAST PATH I136
J 0
(700 4350);
DISPLAY 1.021277 (700 4350);
PAINT ORANGE (700 4350);
DISPLAY INVISIBLE (700 4350);
FORCEPROP 1 LAST COMMENT_BODY TRUE
J 0
(425 4200);
DISPLAY 0.936170 (425 4200);
PAINT GREEN (425 4200);
DISPLAY INVISIBLE (425 4200);
FORCEPROP 1 LAST OFFPAGE TRUE
J 0
(800 4175);
DISPLAY 0.936170 (800 4175);
PAINT GREEN (800 4175);
DISPLAY INVISIBLE (800 4175);
FORCEPROP 2 LAST CDS_LIB mstr_standard
J 0
(475 4300);
DISPLAY 0.787234 (475 4300);
PAINT MONO (475 4300);
DISPLAY INVISIBLE (475 4300);
FORCEADD GND..1
R 2
(2725 950);
FORCEPROP 3 LASTPIN (2725 1000) SIG_NAME GND\g
J 0
(2735 1010);
DISPLAY 0.659574 (2735 1010);
PAINT MONO (2735 1010);
DISPLAY INVISIBLE (2735 1010);
FORCEPROP 1 LAST HDL_POWER GND
J 2
(2725 1100);
DISPLAY 0.553191 (2725 1100);
PAINT GREEN (2725 1100);
DISPLAY INVISIBLE (2725 1100);
FORCEPROP 2 LAST ROOM DDR4_CH_A
J 0
(2725 955);
PAINT ORANGE (2725 955);
DISPLAY INVISIBLE (2725 955);
FORCEPROP 1 LAST PATH I137
J 2
(2650 950);
DISPLAY 0.872340 (2650 950);
PAINT AQUA (2650 950);
DISPLAY INVISIBLE (2650 950);
FORCEPROP 1 LAST BODY_TYPE PLUMBING
J 2
(2770 907);
DISPLAY 0.340426 (2770 907);
PAINT GREEN (2770 907);
DISPLAY INVISIBLE (2770 907);
FORCEPROP 2 LAST BOM_COST MEM
J 0
(2725 955);
PAINT ORANGE (2725 955);
DISPLAY INVISIBLE (2725 955);
FORCEPROP 2 LAST CDS_LIB mstr_symbols
J 0
(2725 950);
DISPLAY 0.787234 (2725 950);
PAINT MONO (2725 950);
DISPLAY INVISIBLE (2725 950);
FORCEPROP 1 LAST SIZE 1B
J 2
(2650 900);
DISPLAY 1.170213 (2650 900);
PAINT GREEN (2650 900);
DISPLAY INVISIBLE (2650 900);
FORCEPROP 1 LAST VOLTAGE 0
J 0
(2725 950);
PAINT SKYBLUE (2725 950);
DISPLAY INVISIBLE (2725 950);
FORCEADD SCONN288_H44441003..3
(3425 2250);
FORCEPROP 2 LASTPIN (2925 1650) $PN 114
J 2
(2915 1660);
DISPLAY 0.617021 (2915 1660);
PAINT ORANGE (2915 1660);
FORCEPROP 1 LAST MATERIAL SCONN
J 0
(2975 3600);
DISPLAY 0.617021 (2975 3600);
PAINT SKYBLUE (2975 3600);
FORCEPROP 2 LASTPIN (3925 1100) $PN 283
J 0
(3935 1110);
DISPLAY 0.617021 (3935 1110);
PAINT ORANGE (3935 1110);
FORCEPROP 2 LASTPIN (3925 1150) $PN 281
J 0
(3935 1160);
DISPLAY 0.617021 (3935 1160);
PAINT ORANGE (3935 1160);
FORCEPROP 2 LASTPIN (3925 1200) $PN 279
J 0
(3935 1210);
DISPLAY 0.617021 (3935 1210);
PAINT ORANGE (3935 1210);
FORCEPROP 2 LASTPIN (3925 1250) $PN 276
J 0
(3935 1260);
DISPLAY 0.617021 (3935 1260);
PAINT ORANGE (3935 1260);
FORCEPROP 2 LASTPIN (3925 1300) $PN 274
J 0
(3935 1310);
DISPLAY 0.617021 (3935 1310);
PAINT ORANGE (3935 1310);
FORCEPROP 2 LASTPIN (3925 1350) $PN 272
J 0
(3935 1360);
DISPLAY 0.617021 (3935 1360);
PAINT ORANGE (3935 1360);
FORCEPROP 2 LASTPIN (3925 1400) $PN 270
J 0
(3935 1410);
DISPLAY 0.617021 (3935 1410);
PAINT ORANGE (3935 1410);
FORCEPROP 2 LASTPIN (3925 1450) $PN 268
J 0
(3935 1460);
DISPLAY 0.617021 (3935 1460);
PAINT ORANGE (3935 1460);
FORCEPROP 2 LASTPIN (3925 1500) $PN 265
J 0
(3935 1510);
DISPLAY 0.617021 (3935 1510);
PAINT ORANGE (3935 1510);
FORCEPROP 2 LASTPIN (3925 1550) $PN 263
J 0
(3935 1560);
DISPLAY 0.617021 (3935 1560);
PAINT ORANGE (3935 1560);
FORCEPROP 2 LASTPIN (3925 1600) $PN 261
J 0
(3935 1610);
DISPLAY 0.617021 (3935 1610);
PAINT ORANGE (3935 1610);
FORCEPROP 2 LASTPIN (3925 1650) $PN 259
J 0
(3935 1660);
DISPLAY 0.617021 (3935 1660);
PAINT ORANGE (3935 1660);
FORCEPROP 2 LASTPIN (3925 1700) $PN 257
J 0
(3935 1710);
DISPLAY 0.617021 (3935 1710);
PAINT ORANGE (3935 1710);
FORCEPROP 2 LASTPIN (3925 1750) $PN 254
J 0
(3935 1760);
DISPLAY 0.617021 (3935 1760);
PAINT ORANGE (3935 1760);
FORCEPROP 2 LASTPIN (3925 1800) $PN 252
J 0
(3935 1810);
DISPLAY 0.617021 (3935 1810);
PAINT ORANGE (3935 1810);
FORCEPROP 2 LASTPIN (3925 1850) $PN 250
J 0
(3935 1860);
DISPLAY 0.617021 (3935 1860);
PAINT ORANGE (3935 1860);
FORCEPROP 2 LASTPIN (3925 1900) $PN 248
J 0
(3935 1910);
DISPLAY 0.617021 (3935 1910);
PAINT ORANGE (3935 1910);
FORCEPROP 2 LASTPIN (3925 1950) $PN 246
J 0
(3935 1960);
DISPLAY 0.617021 (3935 1960);
PAINT ORANGE (3935 1960);
FORCEPROP 2 LASTPIN (3925 2000) $PN 243
J 0
(3935 2010);
DISPLAY 0.617021 (3935 2010);
PAINT ORANGE (3935 2010);
FORCEPROP 2 LASTPIN (3925 2050) $PN 241
J 0
(3935 2060);
DISPLAY 0.617021 (3935 2060);
PAINT ORANGE (3935 2060);
FORCEPROP 2 LASTPIN (3925 2100) $PN 239
J 0
(3935 2110);
DISPLAY 0.617021 (3935 2110);
PAINT ORANGE (3935 2110);
FORCEPROP 2 LASTPIN (3925 2150) $PN 202
J 0
(3935 2160);
DISPLAY 0.617021 (3935 2160);
PAINT ORANGE (3935 2160);
FORCEPROP 2 LASTPIN (3925 2200) $PN 200
J 0
(3935 2210);
DISPLAY 0.617021 (3935 2210);
PAINT ORANGE (3935 2210);
FORCEPROP 2 LASTPIN (3925 2250) $PN 198
J 0
(3935 2260);
DISPLAY 0.617021 (3935 2260);
PAINT ORANGE (3935 2260);
FORCEPROP 2 LASTPIN (3925 2300) $PN 195
J 0
(3935 2310);
DISPLAY 0.617021 (3935 2310);
PAINT ORANGE (3935 2310);
FORCEPROP 2 LASTPIN (3925 2350) $PN 193
J 0
(3935 2360);
DISPLAY 0.617021 (3935 2360);
PAINT ORANGE (3935 2360);
FORCEPROP 2 LASTPIN (3925 2400) $PN 191
J 0
(3935 2410);
DISPLAY 0.617021 (3935 2410);
PAINT ORANGE (3935 2410);
FORCEPROP 2 LASTPIN (3925 2450) $PN 189
J 0
(3935 2460);
DISPLAY 0.617021 (3935 2460);
PAINT ORANGE (3935 2460);
FORCEPROP 2 LASTPIN (3925 2500) $PN 187
J 0
(3935 2510);
DISPLAY 0.617021 (3935 2510);
PAINT ORANGE (3935 2510);
FORCEPROP 2 LASTPIN (3925 2550) $PN 184
J 0
(3935 2560);
DISPLAY 0.617021 (3935 2560);
PAINT ORANGE (3935 2560);
FORCEPROP 2 LASTPIN (3925 2600) $PN 182
J 0
(3935 2610);
DISPLAY 0.617021 (3935 2610);
PAINT ORANGE (3935 2610);
FORCEPROP 2 LASTPIN (3925 2650) $PN 180
J 0
(3935 2660);
DISPLAY 0.617021 (3935 2660);
PAINT ORANGE (3935 2660);
FORCEPROP 2 LASTPIN (3925 2700) $PN 178
J 0
(3935 2710);
DISPLAY 0.617021 (3935 2710);
PAINT ORANGE (3935 2710);
FORCEPROP 2 LASTPIN (3925 2750) $PN 176
J 0
(3935 2760);
DISPLAY 0.617021 (3935 2760);
PAINT ORANGE (3935 2760);
FORCEPROP 2 LASTPIN (3925 2800) $PN 173
J 0
(3935 2810);
DISPLAY 0.617021 (3935 2810);
PAINT ORANGE (3935 2810);
FORCEPROP 2 LASTPIN (3925 2850) $PN 171
J 0
(3935 2860);
DISPLAY 0.617021 (3935 2860);
PAINT ORANGE (3935 2860);
FORCEPROP 2 LASTPIN (3925 2900) $PN 169
J 0
(3935 2910);
DISPLAY 0.617021 (3935 2910);
PAINT ORANGE (3935 2910);
FORCEPROP 2 LASTPIN (3925 2950) $PN 167
J 0
(3935 2960);
DISPLAY 0.617021 (3935 2960);
PAINT ORANGE (3935 2960);
FORCEPROP 2 LASTPIN (3925 3000) $PN 165
J 0
(3935 3010);
DISPLAY 0.617021 (3935 3010);
PAINT ORANGE (3935 3010);
FORCEPROP 2 LASTPIN (3925 3050) $PN 162
J 0
(3935 3060);
DISPLAY 0.617021 (3935 3060);
PAINT ORANGE (3935 3060);
FORCEPROP 2 LASTPIN (3925 3100) $PN 160
J 0
(3935 3110);
DISPLAY 0.617021 (3935 3110);
PAINT ORANGE (3935 3110);
FORCEPROP 2 LASTPIN (3925 3150) $PN 158
J 0
(3935 3160);
DISPLAY 0.617021 (3935 3160);
PAINT ORANGE (3935 3160);
FORCEPROP 2 LASTPIN (3925 3200) $PN 156
J 0
(3935 3210);
DISPLAY 0.617021 (3935 3210);
PAINT ORANGE (3935 3210);
FORCEPROP 2 LASTPIN (3925 3250) $PN 154
J 0
(3935 3260);
DISPLAY 0.617021 (3935 3260);
PAINT ORANGE (3935 3260);
FORCEPROP 2 LASTPIN (3925 3300) $PN 151
J 0
(3935 3310);
DISPLAY 0.617021 (3935 3310);
PAINT ORANGE (3935 3310);
FORCEPROP 2 LASTPIN (3925 3350) $PN 149
J 0
(3935 3360);
DISPLAY 0.617021 (3935 3360);
PAINT ORANGE (3935 3360);
FORCEPROP 2 LASTPIN (3925 3400) $PN 147
J 0
(3935 3410);
DISPLAY 0.617021 (3935 3410);
PAINT ORANGE (3935 3410);
FORCEPROP 2 LASTPIN (2925 1100) $PN 138
J 2
(2915 1110);
DISPLAY 0.617021 (2915 1110);
PAINT ORANGE (2915 1110);
FORCEPROP 2 LASTPIN (2925 1150) $PN 136
J 2
(2915 1160);
DISPLAY 0.617021 (2915 1160);
PAINT ORANGE (2915 1160);
FORCEPROP 2 LASTPIN (2925 1250) $PN 131
J 2
(2915 1260);
DISPLAY 0.617021 (2915 1260);
PAINT ORANGE (2915 1260);
FORCEPROP 2 LASTPIN (2925 1300) $PN 129
J 2
(2915 1310);
DISPLAY 0.617021 (2915 1310);
PAINT ORANGE (2915 1310);
FORCEPROP 2 LASTPIN (2925 1350) $PN 127
J 2
(2915 1360);
DISPLAY 0.617021 (2915 1360);
PAINT ORANGE (2915 1360);
FORCEPROP 2 LASTPIN (2925 1400) $PN 125
J 2
(2915 1410);
DISPLAY 0.617021 (2915 1410);
PAINT ORANGE (2915 1410);
FORCEPROP 2 LASTPIN (2925 1450) $PN 123
J 2
(2915 1460);
DISPLAY 0.617021 (2915 1460);
PAINT ORANGE (2915 1460);
FORCEPROP 2 LASTPIN (2925 1500) $PN 120
J 2
(2915 1510);
DISPLAY 0.617021 (2915 1510);
PAINT ORANGE (2915 1510);
FORCEPROP 2 LASTPIN (2925 1550) $PN 118
J 2
(2915 1560);
DISPLAY 0.617021 (2915 1560);
PAINT ORANGE (2915 1560);
FORCEPROP 2 LASTPIN (2925 1600) $PN 116
J 2
(2915 1610);
DISPLAY 0.617021 (2915 1610);
PAINT ORANGE (2915 1610);
FORCEPROP 2 LASTPIN (2925 1700) $PN 112
J 2
(2915 1710);
DISPLAY 0.617021 (2915 1710);
PAINT ORANGE (2915 1710);
FORCEPROP 2 LASTPIN (2925 1750) $PN 109
J 2
(2915 1760);
DISPLAY 0.617021 (2915 1760);
PAINT ORANGE (2915 1760);
FORCEPROP 2 LASTPIN (2925 1800) $PN 107
J 2
(2915 1810);
DISPLAY 0.617021 (2915 1810);
PAINT ORANGE (2915 1810);
FORCEPROP 2 LASTPIN (2925 1850) $PN 105
J 2
(2915 1860);
DISPLAY 0.617021 (2915 1860);
PAINT ORANGE (2915 1860);
FORCEPROP 2 LASTPIN (2925 1900) $PN 103
J 2
(2915 1910);
DISPLAY 0.617021 (2915 1910);
PAINT ORANGE (2915 1910);
FORCEPROP 2 LASTPIN (2925 1950) $PN 101
J 2
(2915 1960);
DISPLAY 0.617021 (2915 1960);
PAINT ORANGE (2915 1960);
FORCEPROP 2 LASTPIN (2925 2000) $PN 98
J 2
(2915 2010);
DISPLAY 0.617021 (2915 2010);
PAINT ORANGE (2915 2010);
FORCEPROP 2 LASTPIN (2925 2050) $PN 96
J 2
(2915 2060);
DISPLAY 0.617021 (2915 2060);
PAINT ORANGE (2915 2060);
FORCEPROP 2 LASTPIN (2925 2100) $PN 94
J 2
(2915 2110);
DISPLAY 0.617021 (2915 2110);
PAINT ORANGE (2915 2110);
FORCEPROP 2 LASTPIN (2925 2150) $PN 57
J 2
(2915 2160);
DISPLAY 0.617021 (2915 2160);
PAINT ORANGE (2915 2160);
FORCEPROP 2 LASTPIN (2925 2200) $PN 55
J 2
(2915 2210);
DISPLAY 0.617021 (2915 2210);
PAINT ORANGE (2915 2210);
FORCEPROP 2 LASTPIN (2925 2300) $PN 50
J 2
(2915 2310);
DISPLAY 0.617021 (2915 2310);
PAINT ORANGE (2915 2310);
FORCEPROP 2 LASTPIN (2925 2350) $PN 48
J 2
(2915 2360);
DISPLAY 0.617021 (2915 2360);
PAINT ORANGE (2915 2360);
FORCEPROP 2 LASTPIN (2925 2400) $PN 46
J 2
(2915 2410);
DISPLAY 0.617021 (2915 2410);
PAINT ORANGE (2915 2410);
FORCEPROP 2 LASTPIN (2925 2450) $PN 44
J 2
(2915 2460);
DISPLAY 0.617021 (2915 2460);
PAINT ORANGE (2915 2460);
FORCEPROP 2 LASTPIN (2925 2500) $PN 42
J 2
(2915 2510);
DISPLAY 0.617021 (2915 2510);
PAINT ORANGE (2915 2510);
FORCEPROP 2 LASTPIN (2925 2550) $PN 39
J 2
(2915 2560);
DISPLAY 0.617021 (2915 2560);
PAINT ORANGE (2915 2560);
FORCEPROP 2 LASTPIN (2925 2600) $PN 37
J 2
(2915 2610);
DISPLAY 0.617021 (2915 2610);
PAINT ORANGE (2915 2610);
FORCEPROP 2 LASTPIN (2925 2650) $PN 35
J 2
(2915 2660);
DISPLAY 0.617021 (2915 2660);
PAINT ORANGE (2915 2660);
FORCEPROP 2 LASTPIN (2925 2700) $PN 33
J 2
(2915 2710);
DISPLAY 0.617021 (2915 2710);
PAINT ORANGE (2915 2710);
FORCEPROP 2 LASTPIN (2925 2750) $PN 31
J 2
(2915 2760);
DISPLAY 0.617021 (2915 2760);
PAINT ORANGE (2915 2760);
FORCEPROP 2 LASTPIN (2925 2800) $PN 28
J 2
(2915 2810);
DISPLAY 0.617021 (2915 2810);
PAINT ORANGE (2915 2810);
FORCEPROP 2 LASTPIN (2925 2850) $PN 26
J 2
(2915 2860);
DISPLAY 0.617021 (2915 2860);
PAINT ORANGE (2915 2860);
FORCEPROP 2 LASTPIN (2925 2900) $PN 24
J 2
(2915 2910);
DISPLAY 0.617021 (2915 2910);
PAINT ORANGE (2915 2910);
FORCEPROP 2 LASTPIN (2925 2950) $PN 22
J 2
(2915 2960);
DISPLAY 0.617021 (2915 2960);
PAINT ORANGE (2915 2960);
FORCEPROP 2 LASTPIN (2925 3000) $PN 20
J 2
(2915 3010);
DISPLAY 0.617021 (2915 3010);
PAINT ORANGE (2915 3010);
FORCEPROP 2 LASTPIN (2925 3050) $PN 17
J 2
(2915 3060);
DISPLAY 0.617021 (2915 3060);
PAINT ORANGE (2915 3060);
FORCEPROP 2 LASTPIN (2925 3100) $PN 15
J 2
(2915 3110);
DISPLAY 0.617021 (2915 3110);
PAINT ORANGE (2915 3110);
FORCEPROP 2 LASTPIN (2925 3150) $PN 13
J 2
(2915 3160);
DISPLAY 0.617021 (2915 3160);
PAINT ORANGE (2915 3160);
FORCEPROP 2 LASTPIN (2925 3200) $PN 11
J 2
(2915 3210);
DISPLAY 0.617021 (2915 3210);
PAINT ORANGE (2915 3210);
FORCEPROP 2 LASTPIN (2925 3250) $PN 9
J 2
(2915 3260);
DISPLAY 0.617021 (2915 3260);
PAINT ORANGE (2915 3260);
FORCEPROP 2 LASTPIN (2925 3300) $PN 6
J 2
(2915 3310);
DISPLAY 0.617021 (2915 3310);
PAINT ORANGE (2915 3310);
FORCEPROP 2 LASTPIN (2925 3350) $PN 4
J 2
(2915 3360);
DISPLAY 0.617021 (2915 3360);
PAINT ORANGE (2915 3360);
FORCEPROP 2 LASTPIN (2925 3400) $PN 2
J 2
(2915 3410);
DISPLAY 0.617021 (2915 3410);
PAINT ORANGE (2915 3410);
FORCEPROP 1 LAST LOCATION J6U1
J 0
(2975 3650);
DISPLAY 0.617021 (2975 3650);
PAINT AQUA (2975 3650);
FORCEPROP 2 LASTPIN (2925 2250) $PN 53
J 2
(2915 2260);
DISPLAY 0.617021 (2915 2260);
PAINT ORANGE (2915 2260);
FORCEPROP 1 LAST PART_NUMBER H44441-003
J 0
(2975 900);
DISPLAY 0.617021 (2975 900);
PAINT BLUE (2975 900);
FORCEPROP 0 LAST BOM_SS NOPOP
J 0
(3145 3621);
DISPLAY 1.021277 (3145 3621);
PAINT BROWN (3145 3621);
DISPLAY BOTH (3145 3621);
FORCEPROP 2 LASTPIN (2925 1200) $PN 134
J 2
(2915 1210);
DISPLAY 0.617021 (2915 1210);
PAINT ORANGE (2915 1210);
FORCEPROP 2 LAST ROOM DDR4_CH_B
J 0
(3425 2250);
PAINT ORANGE (3425 2250);
DISPLAY INVISIBLE (3425 2250);
FORCEPROP 1 LAST PATH I138
J 0
(3425 3600);
PAINT GREEN (3425 3600);
DISPLAY INVISIBLE (3425 3600);
FORCEPROP 2 LAST CDS_LOCATION J6U1
J 0
(2975 3650);
DISPLAY 0.617021 (2975 3650);
PAINT AQUA (2975 3650);
DISPLAY INVISIBLE (2975 3650);
FORCEPROP 2 LAST SEC 3
J 0
(2975 3700);
DISPLAY 0.680851 (2975 3700);
PAINT MONO (2975 3700);
DISPLAY INVISIBLE (2975 3700);
FORCEPROP 2 LAST SEC_TYPE PIP
J 0
(2975 3700);
DISPLAY 1.021277 (2975 3700);
PAINT ORANGE (2975 3700);
DISPLAY INVISIBLE (2975 3700);
FORCEPROP 2 LAST CDS_LIB mstr_sconn
J 0
(3425 2250);
PAINT ORANGE (3425 2250);
DISPLAY INVISIBLE (3425 2250);
FORCEPROP 2 LAST BOM_COST MEM
J 0
(3425 2250);
PAINT ORANGE (3425 2250);
DISPLAY INVISIBLE (3425 2250);
FORCEPROP 1 LAST PACK_TYPE PIP
J 0
(2975 3700);
PAINT SKYBLUE (2975 3700);
DISPLAY INVISIBLE (2975 3700);
FORCEADD SCONN288_H44441003..1
(-825 2600);
FORCEPROP 2 LASTPIN (-325 3050) $PN 247
J 0
(-315 3060);
DISPLAY 0.617021 (-315 3060);
PAINT ORANGE (-315 3060);
FORCEPROP 2 LASTPIN (-325 1850) $PN 166
J 0
(-315 1860);
DISPLAY 0.617021 (-315 1860);
PAINT ORANGE (-315 1860);
FORCEPROP 2 LASTPIN (-325 1750) $PN 159
J 0
(-315 1760);
DISPLAY 0.617021 (-315 1760);
PAINT ORANGE (-315 1760);
FORCEPROP 2 LASTPIN (-325 1650) $PN 168
J 0
(-315 1660);
DISPLAY 0.617021 (-315 1660);
PAINT ORANGE (-315 1660);
FORCEPROP 2 LASTPIN (-1325 4100) $PN 228
J 2
(-1335 4110);
DISPLAY 0.617021 (-1335 4110);
PAINT ORANGE (-1335 4110);
FORCEPROP 2 LASTPIN (-1325 3400) $PN 79
J 2
(-1335 3410);
DISPLAY 0.617021 (-1335 3410);
PAINT ORANGE (-1335 3410);
FORCEPROP 2 LASTPIN (-1325 3450) $PN 72
J 2
(-1335 3460);
DISPLAY 0.617021 (-1335 3460);
PAINT ORANGE (-1335 3460);
FORCEPROP 2 LASTPIN (-1325 3500) $PN 216
J 2
(-1335 3510);
DISPLAY 0.617021 (-1335 3510);
PAINT ORANGE (-1335 3510);
FORCEPROP 2 LASTPIN (-1325 3550) $PN 71
J 2
(-1335 3560);
DISPLAY 0.617021 (-1335 3560);
PAINT ORANGE (-1335 3560);
FORCEPROP 2 LASTPIN (-1325 3600) $PN 214
J 2
(-1335 3610);
DISPLAY 0.617021 (-1335 3610);
PAINT ORANGE (-1335 3610);
FORCEPROP 2 LASTPIN (-1325 3650) $PN 213
J 2
(-1335 3660);
DISPLAY 0.617021 (-1335 3660);
PAINT ORANGE (-1335 3660);
FORCEPROP 2 LASTPIN (-1325 3750) $PN 211
J 2
(-1335 3760);
DISPLAY 0.617021 (-1335 3760);
PAINT ORANGE (-1335 3760);
FORCEPROP 2 LASTPIN (-1325 3800) $PN 68
J 2
(-1335 3810);
DISPLAY 0.617021 (-1335 3810);
PAINT ORANGE (-1335 3810);
FORCEPROP 2 LASTPIN (-1325 3850) $PN 66
J 2
(-1335 3860);
DISPLAY 0.617021 (-1335 3860);
PAINT ORANGE (-1335 3860);
FORCEPROP 2 LASTPIN (-1325 3900) $PN 225
J 2
(-1335 3910);
DISPLAY 0.617021 (-1335 3910);
PAINT ORANGE (-1335 3910);
FORCEPROP 2 LASTPIN (-1325 3950) $PN 210
J 2
(-1335 3960);
DISPLAY 0.617021 (-1335 3960);
PAINT ORANGE (-1335 3960);
FORCEPROP 2 LASTPIN (-1325 4000) $PN 65
J 2
(-1335 4010);
DISPLAY 0.617021 (-1335 4010);
PAINT ORANGE (-1335 4010);
FORCEPROP 2 LASTPIN (-1325 4050) $PN 232
J 2
(-1335 4060);
DISPLAY 0.617021 (-1335 4060);
PAINT ORANGE (-1335 4060);
FORCEPROP 2 LASTPIN (-1325 4150) $PN 86
J 2
(-1335 4160);
DISPLAY 0.617021 (-1335 4160);
PAINT ORANGE (-1335 4160);
FORCEPROP 2 LASTPIN (-1325 4200) $PN 82
J 2
(-1335 4210);
DISPLAY 0.617021 (-1335 4210);
PAINT ORANGE (-1335 4210);
FORCEPROP 2 LASTPIN (-1325 4250) $PN 234
J 2
(-1335 4260);
DISPLAY 0.617021 (-1335 4260);
PAINT ORANGE (-1335 4260);
FORCEPROP 2 LASTPIN (-1325 1550) $PN 62
J 2
(-1335 1560);
DISPLAY 0.617021 (-1335 1560);
PAINT ORANGE (-1335 1560);
FORCEPROP 2 LASTPIN (-1325 1600) $PN 208
J 2
(-1335 1610);
DISPLAY 0.617021 (-1335 1610);
PAINT ORANGE (-1335 1610);
FORCEPROP 2 LASTPIN (-1325 3250) $PN 81
J 2
(-1335 3260);
DISPLAY 0.617021 (-1335 3260);
PAINT ORANGE (-1335 3260);
FORCEPROP 2 LASTPIN (-1325 3300) $PN 224
J 2
(-1335 3310);
DISPLAY 0.617021 (-1335 3310);
PAINT ORANGE (-1335 3310);
FORCEPROP 2 LASTPIN (-1325 3150) $PN 63
J 2
(-1335 3160);
DISPLAY 0.617021 (-1335 3160);
PAINT ORANGE (-1335 3160);
FORCEPROP 2 LASTPIN (-1325 3200) $PN 207
J 2
(-1335 3210);
DISPLAY 0.617021 (-1335 3210);
PAINT ORANGE (-1335 3210);
FORCEPROP 2 LASTPIN (-1325 2800) $PN 235
J 2
(-1335 2810);
DISPLAY 0.617021 (-1335 2810);
PAINT ORANGE (-1335 2810);
FORCEPROP 2 LASTPIN (-1325 1850) $PN 49
J 2
(-1335 1860);
DISPLAY 0.617021 (-1335 1860);
PAINT ORANGE (-1335 1860);
FORCEPROP 2 LASTPIN (-1325 1900) $PN 194
J 2
(-1335 1910);
DISPLAY 0.617021 (-1335 1910);
PAINT ORANGE (-1335 1910);
FORCEPROP 2 LASTPIN (-1325 1950) $PN 56
J 2
(-1335 1960);
DISPLAY 0.617021 (-1335 1960);
PAINT ORANGE (-1335 1960);
FORCEPROP 2 LASTPIN (-1325 2000) $PN 201
J 2
(-1335 2010);
DISPLAY 0.617021 (-1335 2010);
PAINT ORANGE (-1335 2010);
FORCEPROP 2 LASTPIN (-1325 2050) $PN 47
J 2
(-1335 2060);
DISPLAY 0.617021 (-1335 2060);
PAINT ORANGE (-1335 2060);
FORCEPROP 2 LASTPIN (-1325 2100) $PN 192
J 2
(-1335 2110);
DISPLAY 0.617021 (-1335 2110);
PAINT ORANGE (-1335 2110);
FORCEPROP 2 LASTPIN (-1325 2150) $PN 54
J 2
(-1335 2160);
DISPLAY 0.617021 (-1335 2160);
PAINT ORANGE (-1335 2160);
FORCEPROP 2 LASTPIN (-1325 2200) $PN 199
J 2
(-1335 2210);
DISPLAY 0.617021 (-1335 2210);
PAINT ORANGE (-1335 2210);
FORCEPROP 2 LASTPIN (-1325 2900) $PN 75
J 2
(-1335 2910);
DISPLAY 0.617021 (-1335 2910);
PAINT ORANGE (-1335 2910);
FORCEPROP 2 LASTPIN (-1325 2950) $PN 74
J 2
(-1335 2960);
DISPLAY 0.617021 (-1335 2960);
PAINT ORANGE (-1335 2960);
FORCEPROP 2 LASTPIN (-1325 3000) $PN 219
J 2
(-1335 3010);
DISPLAY 0.617021 (-1335 3010);
PAINT ORANGE (-1335 3010);
FORCEPROP 2 LASTPIN (-1325 3050) $PN 218
J 2
(-1335 3060);
DISPLAY 0.617021 (-1335 3060);
PAINT ORANGE (-1335 3060);
FORCEPROP 2 LASTPIN (-1325 2450) $PN 60
J 2
(-1335 2460);
DISPLAY 0.617021 (-1335 2460);
PAINT ORANGE (-1335 2460);
FORCEPROP 2 LASTPIN (-1325 2500) $PN 203
J 2
(-1335 2510);
DISPLAY 0.617021 (-1335 2510);
PAINT ORANGE (-1335 2510);
FORCEPROP 2 LASTPIN (-325 1100) $PN 5
J 0
(-315 1110);
DISPLAY 0.617021 (-315 1110);
PAINT ORANGE (-315 1110);
FORCEPROP 2 LASTPIN (-325 1150) $PN 150
J 0
(-315 1160);
DISPLAY 0.617021 (-315 1160);
PAINT ORANGE (-315 1160);
FORCEPROP 2 LASTPIN (-325 1200) $PN 12
J 0
(-315 1210);
DISPLAY 0.617021 (-315 1210);
PAINT ORANGE (-315 1210);
FORCEPROP 2 LASTPIN (-325 1250) $PN 157
J 0
(-315 1260);
DISPLAY 0.617021 (-315 1260);
PAINT ORANGE (-315 1260);
FORCEPROP 2 LASTPIN (-325 1300) $PN 3
J 0
(-315 1310);
DISPLAY 0.617021 (-315 1310);
PAINT ORANGE (-315 1310);
FORCEPROP 2 LASTPIN (-325 1350) $PN 148
J 0
(-315 1360);
DISPLAY 0.617021 (-315 1360);
PAINT ORANGE (-315 1360);
FORCEPROP 2 LASTPIN (-325 1400) $PN 10
J 0
(-315 1410);
DISPLAY 0.617021 (-315 1410);
PAINT ORANGE (-315 1410);
FORCEPROP 2 LASTPIN (-325 1450) $PN 155
J 0
(-315 1460);
DISPLAY 0.617021 (-315 1460);
PAINT ORANGE (-315 1460);
FORCEPROP 2 LASTPIN (-325 1500) $PN 16
J 0
(-315 1510);
DISPLAY 0.617021 (-315 1510);
PAINT ORANGE (-315 1510);
FORCEPROP 2 LASTPIN (-325 1550) $PN 161
J 0
(-315 1560);
DISPLAY 0.617021 (-315 1560);
PAINT ORANGE (-315 1560);
FORCEPROP 2 LASTPIN (-325 1600) $PN 23
J 0
(-315 1610);
DISPLAY 0.617021 (-315 1610);
PAINT ORANGE (-315 1610);
FORCEPROP 2 LASTPIN (-325 1700) $PN 14
J 0
(-315 1710);
DISPLAY 0.617021 (-315 1710);
PAINT ORANGE (-315 1710);
FORCEPROP 2 LASTPIN (-325 1800) $PN 21
J 0
(-315 1810);
DISPLAY 0.617021 (-315 1810);
PAINT ORANGE (-315 1810);
FORCEPROP 2 LASTPIN (-325 1900) $PN 27
J 0
(-315 1910);
DISPLAY 0.617021 (-315 1910);
PAINT ORANGE (-315 1910);
FORCEPROP 2 LASTPIN (-325 1950) $PN 172
J 0
(-315 1960);
DISPLAY 0.617021 (-315 1960);
PAINT ORANGE (-315 1960);
FORCEPROP 2 LASTPIN (-325 2000) $PN 34
J 0
(-315 2010);
DISPLAY 0.617021 (-315 2010);
PAINT ORANGE (-315 2010);
FORCEPROP 2 LASTPIN (-325 2050) $PN 179
J 0
(-315 2060);
DISPLAY 0.617021 (-315 2060);
PAINT ORANGE (-315 2060);
FORCEPROP 2 LASTPIN (-325 2100) $PN 25
J 0
(-315 2110);
DISPLAY 0.617021 (-315 2110);
PAINT ORANGE (-315 2110);
FORCEPROP 2 LASTPIN (-325 2150) $PN 170
J 0
(-315 2160);
DISPLAY 0.617021 (-315 2160);
PAINT ORANGE (-315 2160);
FORCEPROP 2 LASTPIN (-325 2200) $PN 32
J 0
(-315 2210);
DISPLAY 0.617021 (-315 2210);
PAINT ORANGE (-315 2210);
FORCEPROP 2 LASTPIN (-325 2250) $PN 177
J 0
(-315 2260);
DISPLAY 0.617021 (-315 2260);
PAINT ORANGE (-315 2260);
FORCEPROP 2 LASTPIN (-325 2300) $PN 38
J 0
(-315 2310);
DISPLAY 0.617021 (-315 2310);
PAINT ORANGE (-315 2310);
FORCEPROP 2 LASTPIN (-325 2350) $PN 183
J 0
(-315 2360);
DISPLAY 0.617021 (-315 2360);
PAINT ORANGE (-315 2360);
FORCEPROP 2 LASTPIN (-325 2400) $PN 45
J 0
(-315 2410);
DISPLAY 0.617021 (-315 2410);
PAINT ORANGE (-315 2410);
FORCEPROP 2 LASTPIN (-325 2450) $PN 190
J 0
(-315 2460);
DISPLAY 0.617021 (-315 2460);
PAINT ORANGE (-315 2460);
FORCEPROP 2 LASTPIN (-325 2500) $PN 36
J 0
(-315 2510);
DISPLAY 0.617021 (-315 2510);
PAINT ORANGE (-315 2510);
FORCEPROP 2 LASTPIN (-325 2550) $PN 181
J 0
(-315 2560);
DISPLAY 0.617021 (-315 2560);
PAINT ORANGE (-315 2560);
FORCEPROP 2 LASTPIN (-325 2600) $PN 43
J 0
(-315 2610);
DISPLAY 0.617021 (-315 2610);
PAINT ORANGE (-315 2610);
FORCEPROP 2 LASTPIN (-325 2650) $PN 188
J 0
(-315 2660);
DISPLAY 0.617021 (-315 2660);
PAINT ORANGE (-315 2660);
FORCEPROP 2 LASTPIN (-325 2700) $PN 97
J 0
(-315 2710);
DISPLAY 0.617021 (-315 2710);
PAINT ORANGE (-315 2710);
FORCEPROP 2 LASTPIN (-325 2750) $PN 242
J 0
(-315 2760);
DISPLAY 0.617021 (-315 2760);
PAINT ORANGE (-315 2760);
FORCEPROP 2 LASTPIN (-325 2800) $PN 104
J 0
(-315 2810);
DISPLAY 0.617021 (-315 2810);
PAINT ORANGE (-315 2810);
FORCEPROP 2 LASTPIN (-325 2850) $PN 249
J 0
(-315 2860);
DISPLAY 0.617021 (-315 2860);
PAINT ORANGE (-315 2860);
FORCEPROP 2 LASTPIN (-325 2900) $PN 95
J 0
(-315 2910);
DISPLAY 0.617021 (-315 2910);
PAINT ORANGE (-315 2910);
FORCEPROP 2 LASTPIN (-325 2950) $PN 240
J 0
(-315 2960);
DISPLAY 0.617021 (-315 2960);
PAINT ORANGE (-315 2960);
FORCEPROP 2 LASTPIN (-325 3000) $PN 102
J 0
(-315 3010);
DISPLAY 0.617021 (-315 3010);
PAINT ORANGE (-315 3010);
FORCEPROP 2 LASTPIN (-325 3100) $PN 108
J 0
(-315 3110);
DISPLAY 0.617021 (-315 3110);
PAINT ORANGE (-315 3110);
FORCEPROP 2 LASTPIN (-325 3150) $PN 253
J 0
(-315 3160);
DISPLAY 0.617021 (-315 3160);
PAINT ORANGE (-315 3160);
FORCEPROP 2 LASTPIN (-325 3200) $PN 115
J 0
(-315 3210);
DISPLAY 0.617021 (-315 3210);
PAINT ORANGE (-315 3210);
FORCEPROP 2 LASTPIN (-325 3250) $PN 260
J 0
(-315 3260);
DISPLAY 0.617021 (-315 3260);
PAINT ORANGE (-315 3260);
FORCEPROP 2 LASTPIN (-325 3300) $PN 106
J 0
(-315 3310);
DISPLAY 0.617021 (-315 3310);
PAINT ORANGE (-315 3310);
FORCEPROP 2 LASTPIN (-325 3350) $PN 251
J 0
(-315 3360);
DISPLAY 0.617021 (-315 3360);
PAINT ORANGE (-315 3360);
FORCEPROP 2 LASTPIN (-325 3400) $PN 113
J 0
(-315 3410);
DISPLAY 0.617021 (-315 3410);
PAINT ORANGE (-315 3410);
FORCEPROP 2 LASTPIN (-325 3450) $PN 258
J 0
(-315 3460);
DISPLAY 0.617021 (-315 3460);
PAINT ORANGE (-315 3460);
FORCEPROP 2 LASTPIN (-325 3500) $PN 119
J 0
(-315 3510);
DISPLAY 0.617021 (-315 3510);
PAINT ORANGE (-315 3510);
FORCEPROP 2 LASTPIN (-325 3550) $PN 264
J 0
(-315 3560);
DISPLAY 0.617021 (-315 3560);
PAINT ORANGE (-315 3560);
FORCEPROP 2 LASTPIN (-325 3600) $PN 126
J 0
(-315 3610);
DISPLAY 0.617021 (-315 3610);
PAINT ORANGE (-315 3610);
FORCEPROP 2 LASTPIN (-325 3650) $PN 271
J 0
(-315 3660);
DISPLAY 0.617021 (-315 3660);
PAINT ORANGE (-315 3660);
FORCEPROP 2 LASTPIN (-325 3700) $PN 117
J 0
(-315 3710);
DISPLAY 0.617021 (-315 3710);
PAINT ORANGE (-315 3710);
FORCEPROP 2 LASTPIN (-325 3750) $PN 262
J 0
(-315 3760);
DISPLAY 0.617021 (-315 3760);
PAINT ORANGE (-315 3760);
FORCEPROP 2 LASTPIN (-325 3800) $PN 124
J 0
(-315 3810);
DISPLAY 0.617021 (-315 3810);
PAINT ORANGE (-315 3810);
FORCEPROP 2 LASTPIN (-325 3850) $PN 269
J 0
(-315 3860);
DISPLAY 0.617021 (-315 3860);
PAINT ORANGE (-315 3860);
FORCEPROP 2 LASTPIN (-325 3900) $PN 130
J 0
(-315 3910);
DISPLAY 0.617021 (-315 3910);
PAINT ORANGE (-315 3910);
FORCEPROP 2 LASTPIN (-325 3950) $PN 275
J 0
(-315 3960);
DISPLAY 0.617021 (-315 3960);
PAINT ORANGE (-315 3960);
FORCEPROP 2 LASTPIN (-325 4000) $PN 137
J 0
(-315 4010);
DISPLAY 0.617021 (-315 4010);
PAINT ORANGE (-315 4010);
FORCEPROP 2 LASTPIN (-325 4050) $PN 282
J 0
(-315 4060);
DISPLAY 0.617021 (-315 4060);
PAINT ORANGE (-315 4060);
FORCEPROP 2 LASTPIN (-325 4100) $PN 128
J 0
(-315 4110);
DISPLAY 0.617021 (-315 4110);
PAINT ORANGE (-315 4110);
FORCEPROP 2 LASTPIN (-325 4150) $PN 273
J 0
(-315 4160);
DISPLAY 0.617021 (-315 4160);
PAINT ORANGE (-315 4160);
FORCEPROP 2 LASTPIN (-325 4200) $PN 135
J 0
(-315 4210);
DISPLAY 0.617021 (-315 4210);
PAINT ORANGE (-315 4210);
FORCEPROP 2 LASTPIN (-325 4250) $PN 280
J 0
(-315 4260);
DISPLAY 0.617021 (-315 4260);
PAINT ORANGE (-315 4260);
FORCEPROP 2 LASTPIN (-1325 1650) $PN 78
J 2
(-1335 1660);
DISPLAY 0.617021 (-1335 1660);
PAINT ORANGE (-1335 1660);
FORCEPROP 2 LASTPIN (-1325 2350) $PN 91
J 2
(-1335 2360);
DISPLAY 0.617021 (-1335 2360);
PAINT ORANGE (-1335 2360);
FORCEPROP 2 LASTPIN (-1325 1750) $PN 222
J 2
(-1335 1760);
DISPLAY 0.617021 (-1335 1760);
PAINT ORANGE (-1335 1760);
FORCEPROP 2 LASTPIN (-1325 1700) $PN 58
J 2
(-1335 1710);
DISPLAY 0.617021 (-1335 1710);
PAINT ORANGE (-1335 1710);
FORCEPROP 2 LASTPIN (-1325 900) $PN 205
J 2
(-1335 910);
DISPLAY 0.617021 (-1335 910);
PAINT ORANGE (-1335 910);
FORCEPROP 2 LASTPIN (-1325 950) $PN 227
J 2
(-1335 960);
DISPLAY 0.617021 (-1335 960);
PAINT ORANGE (-1335 960);
FORCEPROP 2 LASTPIN (-1325 1000) $PN 144
J 2
(-1335 1010);
DISPLAY 0.617021 (-1335 1010);
PAINT ORANGE (-1335 1010);
FORCEPROP 2 LASTPIN (-1325 2600) $PN 84
J 2
(-1335 2610);
DISPLAY 0.617021 (-1335 2610);
PAINT ORANGE (-1335 2610);
FORCEPROP 2 LASTPIN (-1325 2650) $PN 89
J 2
(-1335 2660);
DISPLAY 0.617021 (-1335 2660);
PAINT ORANGE (-1335 2660);
FORCEPROP 2 LASTPIN (-1325 2700) $PN 93
J 2
(-1335 2710);
DISPLAY 0.617021 (-1335 2710);
PAINT ORANGE (-1335 2710);
FORCEPROP 2 LASTPIN (-1325 2750) $PN 237
J 2
(-1335 2760);
DISPLAY 0.617021 (-1335 2760);
PAINT ORANGE (-1335 2760);
FORCEPROP 2 LASTPIN (-1325 1300) $PN 139
J 2
(-1335 1310);
DISPLAY 0.617021 (-1335 1310);
PAINT ORANGE (-1335 1310);
FORCEPROP 2 LASTPIN (-1325 1350) $PN 140
J 2
(-1335 1360);
DISPLAY 0.617021 (-1335 1360);
PAINT ORANGE (-1335 1360);
FORCEPROP 2 LASTPIN (-1325 1400) $PN 238
J 2
(-1335 1410);
DISPLAY 0.617021 (-1335 1410);
PAINT ORANGE (-1335 1410);
FORCEPROP 2 LASTPIN (-1325 800) $PN 230
J 2
(-1335 810);
DISPLAY 0.617021 (-1335 810);
PAINT ORANGE (-1335 810);
FORCEPROP 2 LASTPIN (-1325 1200) $PN 141
J 2
(-1335 1210);
DISPLAY 0.617021 (-1335 1210);
PAINT ORANGE (-1335 1210);
FORCEPROP 2 LASTPIN (-1325 1250) $PN 285
J 2
(-1335 1260);
DISPLAY 0.617021 (-1335 1260);
PAINT ORANGE (-1335 1260);
FORCEPROP 2 LASTPIN (-1325 1450) $PN 284
J 2
(-1335 1460);
DISPLAY 0.617021 (-1335 1460);
PAINT ORANGE (-1335 1460);
FORCEPROP 2 LASTPIN (-1325 1100) $PN 146
J 2
(-1335 1110);
DISPLAY 0.617021 (-1335 1110);
PAINT ORANGE (-1335 1110);
FORCEPROP 1 LAST PART_NUMBER H44441-003
J 0
(-1275 600);
DISPLAY 0.617021 (-1275 600);
PAINT BLUE (-1275 600);
FORCEPROP 2 LASTPIN (-1325 2300) $PN 87
J 2
(-1335 2310);
DISPLAY 0.617021 (-1335 2310);
PAINT ORANGE (-1335 2310);
FORCEPROP 1 LAST LOCATION J6U1
J 0
(-1275 4500);
DISPLAY 0.617021 (-1275 4500);
PAINT AQUA (-1275 4500);
FORCEPROP 1 LAST MATERIAL SCONN
J 0
(-1275 4450);
DISPLAY 0.617021 (-1275 4450);
PAINT SKYBLUE (-1275 4450);
FORCEPROP 0 LAST BOM_SS NOPOP
J 0
(-1030 4471);
DISPLAY 1.021277 (-1030 4471);
PAINT BROWN (-1030 4471);
DISPLAY BOTH (-1030 4471);
FORCEPROP 2 LASTPIN (-1325 3700) $PN 69
J 2
(-1335 3710);
DISPLAY 0.617021 (-1335 3710);
PAINT ORANGE (-1335 3710);
FORCEPROP 2 LAST ROOM DDR4_CH_B
J 0
(-825 2600);
PAINT ORANGE (-825 2600);
DISPLAY INVISIBLE (-825 2600);
FORCEPROP 1 LAST PATH I14
J 0
(-825 4450);
PAINT GREEN (-825 4450);
DISPLAY INVISIBLE (-825 4450);
FORCEPROP 2 LAST CDS_LOCATION J6U1
J 0
(-1275 4500);
DISPLAY 0.617021 (-1275 4500);
PAINT AQUA (-1275 4500);
DISPLAY INVISIBLE (-1275 4500);
FORCEPROP 2 LAST SEC 1
J 0
(-1275 4550);
DISPLAY 0.680851 (-1275 4550);
PAINT MONO (-1275 4550);
DISPLAY INVISIBLE (-1275 4550);
FORCEPROP 2 LAST SEC_TYPE PIP
J 0
(-1275 4550);
DISPLAY 1.021277 (-1275 4550);
PAINT ORANGE (-1275 4550);
DISPLAY INVISIBLE (-1275 4550);
FORCEPROP 2 LAST CDS_LIB mstr_sconn
J 0
(-825 2600);
PAINT ORANGE (-825 2600);
DISPLAY INVISIBLE (-825 2600);
FORCEPROP 2 LAST BOM_COST MEM
J 0
(-825 2600);
PAINT ORANGE (-825 2600);
DISPLAY INVISIBLE (-825 2600);
FORCEPROP 1 LAST PACK_TYPE PIP
J 0
(-1275 4550);
PAINT SKYBLUE (-1275 4550);
DISPLAY INVISIBLE (-1275 4550);
FORCEADD TAP..6
R 2
(2325 3100);
FORCEPROP 3 LASTPIN (2275 3100) SIG_NAME M_B_DQS_DP<0>
J 0
(2285 3110);
DISPLAY 0.659574 (2285 3110);
PAINT MONO (2285 3110);
DISPLAY INVISIBLE (2285 3110);
FORCEPROP 1 LASTPIN (2275 3100) BN 0
J 2
(2325 3110);
DISPLAY 0.617021 (2325 3110);
PAINT PINK (2325 3110);
FORCEPROP 1 LAST PATH I142
J 2
(2327 3100);
DISPLAY 0.872340 (2327 3100);
PAINT GREEN (2327 3100);
DISPLAY INVISIBLE (2327 3100);
FORCEPROP 1 LAST HDL_TAP TRUE
J 2
(2000 2975);
DISPLAY 1.234043 (2000 2975);
PAINT GREEN (2000 2975);
DISPLAY INVISIBLE (2000 2975);
FORCEPROP 1 LAST BODY_TYPE PLUMBING
J 2
(2325 3050);
DISPLAY 1.234043 (2325 3050);
PAINT GREEN (2325 3050);
DISPLAY INVISIBLE (2325 3050);
FORCEPROP 2 LAST CDS_LIB mstr_standard
J 0
(2325 3100);
DISPLAY 0.787234 (2325 3100);
PAINT MONO (2325 3100);
DISPLAY INVISIBLE (2325 3100);
FORCEADD TAP..6
R 2
(2325 3200);
FORCEPROP 3 LASTPIN (2275 3200) SIG_NAME M_B_DQS_DP<1>
J 0
(2285 3210);
DISPLAY 0.659574 (2285 3210);
PAINT MONO (2285 3210);
DISPLAY INVISIBLE (2285 3210);
FORCEPROP 1 LASTPIN (2275 3200) BN 1
J 2
(2325 3210);
DISPLAY 0.617021 (2325 3210);
PAINT PINK (2325 3210);
FORCEPROP 1 LAST PATH I143
J 2
(2327 3200);
DISPLAY 0.872340 (2327 3200);
PAINT GREEN (2327 3200);
DISPLAY INVISIBLE (2327 3200);
FORCEPROP 1 LAST HDL_TAP TRUE
J 2
(2000 3075);
DISPLAY 1.234043 (2000 3075);
PAINT GREEN (2000 3075);
DISPLAY INVISIBLE (2000 3075);
FORCEPROP 1 LAST BODY_TYPE PLUMBING
J 2
(2325 3150);
DISPLAY 1.234043 (2325 3150);
PAINT GREEN (2325 3150);
DISPLAY INVISIBLE (2325 3150);
FORCEPROP 2 LAST CDS_LIB mstr_standard
J 0
(2325 3200);
DISPLAY 0.787234 (2325 3200);
PAINT MONO (2325 3200);
DISPLAY INVISIBLE (2325 3200);
FORCEADD TAP..6
R 2
(2525 3050);
FORCEPROP 3 LASTPIN (2475 3050) SIG_NAME M_B_DQS_DN<0>
J 0
(2485 3060);
DISPLAY 0.659574 (2485 3060);
PAINT MONO (2485 3060);
DISPLAY INVISIBLE (2485 3060);
FORCEPROP 1 LASTPIN (2475 3050) BN 0
J 2
(2525 3060);
DISPLAY 0.617021 (2525 3060);
PAINT PINK (2525 3060);
FORCEPROP 1 LAST PATH I144
J 2
(2527 3050);
DISPLAY 0.872340 (2527 3050);
PAINT GREEN (2527 3050);
DISPLAY INVISIBLE (2527 3050);
FORCEPROP 1 LAST HDL_TAP TRUE
J 2
(2200 2925);
DISPLAY 1.234043 (2200 2925);
PAINT GREEN (2200 2925);
DISPLAY INVISIBLE (2200 2925);
FORCEPROP 1 LAST BODY_TYPE PLUMBING
J 2
(2525 3000);
DISPLAY 1.234043 (2525 3000);
PAINT GREEN (2525 3000);
DISPLAY INVISIBLE (2525 3000);
FORCEPROP 2 LAST CDS_LIB mstr_standard
J 0
(2525 3050);
DISPLAY 0.787234 (2525 3050);
PAINT MONO (2525 3050);
DISPLAY INVISIBLE (2525 3050);
FORCEADD TAP..6
R 2
(2525 3150);
FORCEPROP 3 LASTPIN (2475 3150) SIG_NAME M_B_DQS_DN<1>
J 0
(2485 3160);
DISPLAY 0.659574 (2485 3160);
PAINT MONO (2485 3160);
DISPLAY INVISIBLE (2485 3160);
FORCEPROP 1 LASTPIN (2475 3150) BN 1
J 2
(2525 3160);
DISPLAY 0.617021 (2525 3160);
PAINT PINK (2525 3160);
FORCEPROP 1 LAST PATH I145
J 2
(2527 3150);
DISPLAY 0.872340 (2527 3150);
PAINT GREEN (2527 3150);
DISPLAY INVISIBLE (2527 3150);
FORCEPROP 1 LAST HDL_TAP TRUE
J 2
(2200 3025);
DISPLAY 1.234043 (2200 3025);
PAINT GREEN (2200 3025);
DISPLAY INVISIBLE (2200 3025);
FORCEPROP 1 LAST BODY_TYPE PLUMBING
J 2
(2525 3100);
DISPLAY 1.234043 (2525 3100);
PAINT GREEN (2525 3100);
DISPLAY INVISIBLE (2525 3100);
FORCEPROP 2 LAST CDS_LIB mstr_standard
J 0
(2525 3150);
DISPLAY 0.787234 (2525 3150);
PAINT MONO (2525 3150);
DISPLAY INVISIBLE (2525 3150);
FORCEADD TAP..6
R 2
(2325 3300);
FORCEPROP 3 LASTPIN (2275 3300) SIG_NAME M_B_DQS_DP<2>
J 0
(2285 3310);
DISPLAY 0.659574 (2285 3310);
PAINT MONO (2285 3310);
DISPLAY INVISIBLE (2285 3310);
FORCEPROP 1 LASTPIN (2275 3300) BN 2
J 2
(2325 3310);
DISPLAY 0.617021 (2325 3310);
PAINT PINK (2325 3310);
FORCEPROP 1 LAST PATH I146
J 2
(2327 3300);
DISPLAY 0.872340 (2327 3300);
PAINT GREEN (2327 3300);
DISPLAY INVISIBLE (2327 3300);
FORCEPROP 1 LAST HDL_TAP TRUE
J 2
(2000 3175);
DISPLAY 1.234043 (2000 3175);
PAINT GREEN (2000 3175);
DISPLAY INVISIBLE (2000 3175);
FORCEPROP 1 LAST BODY_TYPE PLUMBING
J 2
(2325 3250);
DISPLAY 1.234043 (2325 3250);
PAINT GREEN (2325 3250);
DISPLAY INVISIBLE (2325 3250);
FORCEPROP 2 LAST CDS_LIB mstr_standard
J 0
(2325 3300);
DISPLAY 0.787234 (2325 3300);
PAINT MONO (2325 3300);
DISPLAY INVISIBLE (2325 3300);
FORCEADD TAP..6
R 2
(2325 3400);
FORCEPROP 3 LASTPIN (2275 3400) SIG_NAME M_B_DQS_DP<3>
J 0
(2285 3410);
DISPLAY 0.659574 (2285 3410);
PAINT MONO (2285 3410);
DISPLAY INVISIBLE (2285 3410);
FORCEPROP 1 LASTPIN (2275 3400) BN 3
J 2
(2325 3410);
DISPLAY 0.617021 (2325 3410);
PAINT PINK (2325 3410);
FORCEPROP 1 LAST PATH I147
J 2
(2327 3400);
DISPLAY 0.872340 (2327 3400);
PAINT GREEN (2327 3400);
DISPLAY INVISIBLE (2327 3400);
FORCEPROP 1 LAST HDL_TAP TRUE
J 2
(2000 3275);
DISPLAY 1.234043 (2000 3275);
PAINT GREEN (2000 3275);
DISPLAY INVISIBLE (2000 3275);
FORCEPROP 1 LAST BODY_TYPE PLUMBING
J 2
(2325 3350);
DISPLAY 1.234043 (2325 3350);
PAINT GREEN (2325 3350);
DISPLAY INVISIBLE (2325 3350);
FORCEPROP 2 LAST CDS_LIB mstr_standard
J 0
(2325 3400);
DISPLAY 0.787234 (2325 3400);
PAINT MONO (2325 3400);
DISPLAY INVISIBLE (2325 3400);
FORCEADD TAP..6
R 2
(2325 3600);
FORCEPROP 3 LASTPIN (2275 3600) SIG_NAME M_B_DQS_DP<5>
J 0
(2285 3610);
DISPLAY 0.659574 (2285 3610);
PAINT MONO (2285 3610);
DISPLAY INVISIBLE (2285 3610);
FORCEPROP 1 LASTPIN (2275 3600) BN 5
J 2
(2325 3610);
DISPLAY 0.617021 (2325 3610);
PAINT PINK (2325 3610);
FORCEPROP 1 LAST PATH I148
J 2
(2327 3600);
DISPLAY 0.872340 (2327 3600);
PAINT GREEN (2327 3600);
DISPLAY INVISIBLE (2327 3600);
FORCEPROP 1 LAST HDL_TAP TRUE
J 2
(2000 3475);
DISPLAY 1.234043 (2000 3475);
PAINT GREEN (2000 3475);
DISPLAY INVISIBLE (2000 3475);
FORCEPROP 1 LAST BODY_TYPE PLUMBING
J 2
(2325 3550);
DISPLAY 1.234043 (2325 3550);
PAINT GREEN (2325 3550);
DISPLAY INVISIBLE (2325 3550);
FORCEPROP 2 LAST CDS_LIB mstr_standard
J 0
(2325 3600);
DISPLAY 0.787234 (2325 3600);
PAINT MONO (2325 3600);
DISPLAY INVISIBLE (2325 3600);
FORCEADD TAP..6
R 2
(2325 3500);
FORCEPROP 3 LASTPIN (2275 3500) SIG_NAME M_B_DQS_DP<4>
J 0
(2285 3510);
DISPLAY 0.659574 (2285 3510);
PAINT MONO (2285 3510);
DISPLAY INVISIBLE (2285 3510);
FORCEPROP 1 LASTPIN (2275 3500) BN 4
J 2
(2325 3510);
DISPLAY 0.617021 (2325 3510);
PAINT PINK (2325 3510);
FORCEPROP 1 LAST PATH I149
J 2
(2327 3500);
DISPLAY 0.872340 (2327 3500);
PAINT GREEN (2327 3500);
DISPLAY INVISIBLE (2327 3500);
FORCEPROP 1 LAST HDL_TAP TRUE
J 2
(2000 3375);
DISPLAY 1.234043 (2000 3375);
PAINT GREEN (2000 3375);
DISPLAY INVISIBLE (2000 3375);
FORCEPROP 1 LAST BODY_TYPE PLUMBING
J 2
(2325 3450);
DISPLAY 1.234043 (2325 3450);
PAINT GREEN (2325 3450);
DISPLAY INVISIBLE (2325 3450);
FORCEPROP 2 LAST CDS_LIB mstr_standard
J 0
(2325 3500);
DISPLAY 0.787234 (2325 3500);
PAINT MONO (2325 3500);
DISPLAY INVISIBLE (2325 3500);
FORCEADD OFFPAGE..1
(-2225 2150);
FORCEPROP 2 LAST $XR5 48 
J 0
(-2926 2150);
DISPLAY 0.638298 (-2926 2150);
PAINT MONO (-2926 2150);
FORCEPROP 2 LAST $XR4 47 
J 0
(-2836 2150);
DISPLAY 0.638298 (-2836 2150);
PAINT MONO (-2836 2150);
FORCEPROP 2 LAST $XR3 45 
J 0
(-2746 2150);
DISPLAY 0.638298 (-2746 2150);
PAINT MONO (-2746 2150);
FORCEPROP 2 LAST $XR2 44 
J 0
(-2656 2150);
DISPLAY 0.638298 (-2656 2150);
PAINT MONO (-2656 2150);
FORCEPROP 2 LAST $XR1 43 
J 0
(-2566 2150);
DISPLAY 0.638298 (-2566 2150);
PAINT MONO (-2566 2150);
FORCEPROP 2 LAST $XR0 21 
J 0
(-2476 2150);
DISPLAY 0.638298 (-2476 2150);
PAINT MONO (-2476 2150);
FORCEPROP 2 LAST PATH I15
J 0
(-2425 2200);
DISPLAY 1.021277 (-2425 2200);
PAINT ORANGE (-2425 2200);
DISPLAY INVISIBLE (-2425 2200);
FORCEPROP 1 LAST COMMENT_BODY TRUE
J 0
(-2100 2050);
DISPLAY 0.936170 (-2100 2050);
PAINT GREEN (-2100 2050);
DISPLAY INVISIBLE (-2100 2050);
FORCEPROP 1 LAST OFFPAGE TRUE
J 0
(-1900 2025);
DISPLAY 0.936170 (-1900 2025);
PAINT GREEN (-1900 2025);
DISPLAY INVISIBLE (-1900 2025);
FORCEPROP 2 LAST CDS_LIB mstr_standard
J 0
(-2225 2150);
DISPLAY 0.787234 (-2225 2150);
PAINT MONO (-2225 2150);
DISPLAY INVISIBLE (-2225 2150);
FORCEADD TAP..6
R 2
(2325 3700);
FORCEPROP 3 LASTPIN (2275 3700) SIG_NAME M_B_DQS_DP<6>
J 0
(2285 3710);
DISPLAY 0.659574 (2285 3710);
PAINT MONO (2285 3710);
DISPLAY INVISIBLE (2285 3710);
FORCEPROP 1 LASTPIN (2275 3700) BN 6
J 2
(2325 3710);
DISPLAY 0.617021 (2325 3710);
PAINT PINK (2325 3710);
FORCEPROP 1 LAST PATH I150
J 2
(2327 3700);
DISPLAY 0.872340 (2327 3700);
PAINT GREEN (2327 3700);
DISPLAY INVISIBLE (2327 3700);
FORCEPROP 1 LAST HDL_TAP TRUE
J 2
(2000 3575);
DISPLAY 1.234043 (2000 3575);
PAINT GREEN (2000 3575);
DISPLAY INVISIBLE (2000 3575);
FORCEPROP 1 LAST BODY_TYPE PLUMBING
J 2
(2325 3650);
DISPLAY 1.234043 (2325 3650);
PAINT GREEN (2325 3650);
DISPLAY INVISIBLE (2325 3650);
FORCEPROP 2 LAST CDS_LIB mstr_standard
J 0
(2325 3700);
DISPLAY 0.787234 (2325 3700);
PAINT MONO (2325 3700);
DISPLAY INVISIBLE (2325 3700);
FORCEADD TAP..6
R 2
(2525 3450);
FORCEPROP 3 LASTPIN (2475 3450) SIG_NAME M_B_DQS_DN<4>
J 0
(2485 3460);
DISPLAY 0.659574 (2485 3460);
PAINT MONO (2485 3460);
DISPLAY INVISIBLE (2485 3460);
FORCEPROP 1 LASTPIN (2475 3450) BN 4
J 2
(2525 3460);
DISPLAY 0.617021 (2525 3460);
PAINT PINK (2525 3460);
FORCEPROP 1 LAST PATH I151
J 2
(2527 3450);
DISPLAY 0.872340 (2527 3450);
PAINT GREEN (2527 3450);
DISPLAY INVISIBLE (2527 3450);
FORCEPROP 1 LAST HDL_TAP TRUE
J 2
(2200 3325);
DISPLAY 1.234043 (2200 3325);
PAINT GREEN (2200 3325);
DISPLAY INVISIBLE (2200 3325);
FORCEPROP 1 LAST BODY_TYPE PLUMBING
J 2
(2525 3400);
DISPLAY 1.234043 (2525 3400);
PAINT GREEN (2525 3400);
DISPLAY INVISIBLE (2525 3400);
FORCEPROP 2 LAST CDS_LIB mstr_standard
J 0
(2525 3450);
DISPLAY 0.787234 (2525 3450);
PAINT MONO (2525 3450);
DISPLAY INVISIBLE (2525 3450);
FORCEADD TAP..6
R 2
(2525 3350);
FORCEPROP 3 LASTPIN (2475 3350) SIG_NAME M_B_DQS_DN<3>
J 0
(2485 3360);
DISPLAY 0.659574 (2485 3360);
PAINT MONO (2485 3360);
DISPLAY INVISIBLE (2485 3360);
FORCEPROP 1 LASTPIN (2475 3350) BN 3
J 2
(2525 3360);
DISPLAY 0.617021 (2525 3360);
PAINT PINK (2525 3360);
FORCEPROP 1 LAST PATH I152
J 2
(2527 3350);
DISPLAY 0.872340 (2527 3350);
PAINT GREEN (2527 3350);
DISPLAY INVISIBLE (2527 3350);
FORCEPROP 1 LAST HDL_TAP TRUE
J 2
(2200 3225);
DISPLAY 1.234043 (2200 3225);
PAINT GREEN (2200 3225);
DISPLAY INVISIBLE (2200 3225);
FORCEPROP 1 LAST BODY_TYPE PLUMBING
J 2
(2525 3300);
DISPLAY 1.234043 (2525 3300);
PAINT GREEN (2525 3300);
DISPLAY INVISIBLE (2525 3300);
FORCEPROP 2 LAST CDS_LIB mstr_standard
J 0
(2525 3350);
DISPLAY 0.787234 (2525 3350);
PAINT MONO (2525 3350);
DISPLAY INVISIBLE (2525 3350);
FORCEADD TAP..6
R 2
(2525 3250);
FORCEPROP 3 LASTPIN (2475 3250) SIG_NAME M_B_DQS_DN<2>
J 0
(2485 3260);
DISPLAY 0.659574 (2485 3260);
PAINT MONO (2485 3260);
DISPLAY INVISIBLE (2485 3260);
FORCEPROP 1 LASTPIN (2475 3250) BN 2
J 2
(2525 3260);
DISPLAY 0.617021 (2525 3260);
PAINT PINK (2525 3260);
FORCEPROP 1 LAST PATH I153
J 2
(2527 3250);
DISPLAY 0.872340 (2527 3250);
PAINT GREEN (2527 3250);
DISPLAY INVISIBLE (2527 3250);
FORCEPROP 1 LAST HDL_TAP TRUE
J 2
(2200 3125);
DISPLAY 1.234043 (2200 3125);
PAINT GREEN (2200 3125);
DISPLAY INVISIBLE (2200 3125);
FORCEPROP 1 LAST BODY_TYPE PLUMBING
J 2
(2525 3200);
DISPLAY 1.234043 (2525 3200);
PAINT GREEN (2525 3200);
DISPLAY INVISIBLE (2525 3200);
FORCEPROP 2 LAST CDS_LIB mstr_standard
J 0
(2525 3250);
DISPLAY 0.787234 (2525 3250);
PAINT MONO (2525 3250);
DISPLAY INVISIBLE (2525 3250);
FORCEADD TAP..6
R 2
(2525 3550);
FORCEPROP 3 LASTPIN (2475 3550) SIG_NAME M_B_DQS_DN<5>
J 0
(2485 3560);
DISPLAY 0.659574 (2485 3560);
PAINT MONO (2485 3560);
DISPLAY INVISIBLE (2485 3560);
FORCEPROP 1 LASTPIN (2475 3550) BN 5
J 2
(2525 3560);
DISPLAY 0.617021 (2525 3560);
PAINT PINK (2525 3560);
FORCEPROP 1 LAST PATH I154
J 2
(2527 3550);
DISPLAY 0.872340 (2527 3550);
PAINT GREEN (2527 3550);
DISPLAY INVISIBLE (2527 3550);
FORCEPROP 1 LAST HDL_TAP TRUE
J 2
(2200 3425);
DISPLAY 1.234043 (2200 3425);
PAINT GREEN (2200 3425);
DISPLAY INVISIBLE (2200 3425);
FORCEPROP 1 LAST BODY_TYPE PLUMBING
J 2
(2525 3500);
DISPLAY 1.234043 (2525 3500);
PAINT GREEN (2525 3500);
DISPLAY INVISIBLE (2525 3500);
FORCEPROP 2 LAST CDS_LIB mstr_standard
J 0
(2525 3550);
DISPLAY 0.787234 (2525 3550);
PAINT MONO (2525 3550);
DISPLAY INVISIBLE (2525 3550);
FORCEADD TAP..6
R 2
(2525 3650);
FORCEPROP 3 LASTPIN (2475 3650) SIG_NAME M_B_DQS_DN<6>
J 0
(2485 3660);
DISPLAY 0.659574 (2485 3660);
PAINT MONO (2485 3660);
DISPLAY INVISIBLE (2485 3660);
FORCEPROP 1 LASTPIN (2475 3650) BN 6
J 2
(2525 3660);
DISPLAY 0.617021 (2525 3660);
PAINT PINK (2525 3660);
FORCEPROP 1 LAST PATH I155
J 2
(2527 3650);
DISPLAY 0.872340 (2527 3650);
PAINT GREEN (2527 3650);
DISPLAY INVISIBLE (2527 3650);
FORCEPROP 1 LAST HDL_TAP TRUE
J 2
(2200 3525);
DISPLAY 1.234043 (2200 3525);
PAINT GREEN (2200 3525);
DISPLAY INVISIBLE (2200 3525);
FORCEPROP 1 LAST BODY_TYPE PLUMBING
J 2
(2525 3600);
DISPLAY 1.234043 (2525 3600);
PAINT GREEN (2525 3600);
DISPLAY INVISIBLE (2525 3600);
FORCEPROP 2 LAST CDS_LIB mstr_standard
J 0
(2525 3650);
DISPLAY 0.787234 (2525 3650);
PAINT MONO (2525 3650);
DISPLAY INVISIBLE (2525 3650);
FORCEADD GND..1
R 2
(4125 950);
FORCEPROP 3 LASTPIN (4125 1000) SIG_NAME GND\g
J 0
(4135 1010);
DISPLAY 0.659574 (4135 1010);
PAINT MONO (4135 1010);
DISPLAY INVISIBLE (4135 1010);
FORCEPROP 1 LAST HDL_POWER GND
J 2
(4125 1100);
DISPLAY 0.553191 (4125 1100);
PAINT GREEN (4125 1100);
DISPLAY INVISIBLE (4125 1100);
FORCEPROP 2 LAST ROOM DDR4_CH_A
J 0
(4125 955);
PAINT ORANGE (4125 955);
DISPLAY INVISIBLE (4125 955);
FORCEPROP 1 LAST PATH I156
J 2
(4050 950);
DISPLAY 0.872340 (4050 950);
PAINT AQUA (4050 950);
DISPLAY INVISIBLE (4050 950);
FORCEPROP 1 LAST BODY_TYPE PLUMBING
J 2
(4170 907);
DISPLAY 0.340426 (4170 907);
PAINT GREEN (4170 907);
DISPLAY INVISIBLE (4170 907);
FORCEPROP 2 LAST BOM_COST MEM
J 0
(4125 955);
PAINT ORANGE (4125 955);
DISPLAY INVISIBLE (4125 955);
FORCEPROP 2 LAST CDS_LIB mstr_symbols
J 0
(4125 950);
DISPLAY 0.787234 (4125 950);
PAINT MONO (4125 950);
DISPLAY INVISIBLE (4125 950);
FORCEPROP 1 LAST SIZE 1B
J 2
(4050 900);
DISPLAY 1.170213 (4050 900);
PAINT GREEN (4050 900);
DISPLAY INVISIBLE (4050 900);
FORCEPROP 1 LAST VOLTAGE 0
J 0
(4125 950);
PAINT SKYBLUE (4125 950);
DISPLAY INVISIBLE (4125 950);
FORCEADD TAP..6
R 2
(2325 3800);
FORCEPROP 3 LASTPIN (2275 3800) SIG_NAME M_B_DQS_DP<7>
J 0
(2285 3810);
DISPLAY 0.659574 (2285 3810);
PAINT MONO (2285 3810);
DISPLAY INVISIBLE (2285 3810);
FORCEPROP 1 LASTPIN (2275 3800) BN 7
J 2
(2325 3810);
DISPLAY 0.617021 (2325 3810);
PAINT PINK (2325 3810);
FORCEPROP 1 LAST PATH I157
J 2
(2327 3800);
DISPLAY 0.872340 (2327 3800);
PAINT GREEN (2327 3800);
DISPLAY INVISIBLE (2327 3800);
FORCEPROP 1 LAST HDL_TAP TRUE
J 2
(2000 3675);
DISPLAY 1.234043 (2000 3675);
PAINT GREEN (2000 3675);
DISPLAY INVISIBLE (2000 3675);
FORCEPROP 1 LAST BODY_TYPE PLUMBING
J 2
(2325 3750);
DISPLAY 1.234043 (2325 3750);
PAINT GREEN (2325 3750);
DISPLAY INVISIBLE (2325 3750);
FORCEPROP 2 LAST CDS_LIB mstr_standard
J 0
(2325 3800);
DISPLAY 0.787234 (2325 3800);
PAINT MONO (2325 3800);
DISPLAY INVISIBLE (2325 3800);
FORCEADD TAP..6
R 2
(2325 4000);
FORCEPROP 3 LASTPIN (2275 4000) SIG_NAME M_B_DQS_DP<9>
J 0
(2285 4010);
DISPLAY 0.659574 (2285 4010);
PAINT MONO (2285 4010);
DISPLAY INVISIBLE (2285 4010);
FORCEPROP 1 LASTPIN (2275 4000) BN 9
J 2
(2325 4010);
DISPLAY 0.617021 (2325 4010);
PAINT PINK (2325 4010);
FORCEPROP 1 LAST PATH I158
J 2
(2327 4000);
DISPLAY 0.872340 (2327 4000);
PAINT GREEN (2327 4000);
DISPLAY INVISIBLE (2327 4000);
FORCEPROP 1 LAST HDL_TAP TRUE
J 2
(2000 3875);
DISPLAY 1.234043 (2000 3875);
PAINT GREEN (2000 3875);
DISPLAY INVISIBLE (2000 3875);
FORCEPROP 1 LAST BODY_TYPE PLUMBING
J 2
(2325 3950);
DISPLAY 1.234043 (2325 3950);
PAINT GREEN (2325 3950);
DISPLAY INVISIBLE (2325 3950);
FORCEPROP 2 LAST CDS_LIB mstr_standard
J 0
(2325 4000);
DISPLAY 0.787234 (2325 4000);
PAINT MONO (2325 4000);
DISPLAY INVISIBLE (2325 4000);
FORCEADD TAP..6
R 2
(2325 3900);
FORCEPROP 3 LASTPIN (2275 3900) SIG_NAME M_B_DQS_DP<8>
J 0
(2285 3910);
DISPLAY 0.659574 (2285 3910);
PAINT MONO (2285 3910);
DISPLAY INVISIBLE (2285 3910);
FORCEPROP 1 LASTPIN (2275 3900) BN 8
J 2
(2325 3910);
DISPLAY 0.617021 (2325 3910);
PAINT PINK (2325 3910);
FORCEPROP 1 LAST PATH I159
J 2
(2327 3900);
DISPLAY 0.872340 (2327 3900);
PAINT GREEN (2327 3900);
DISPLAY INVISIBLE (2327 3900);
FORCEPROP 1 LAST HDL_TAP TRUE
J 2
(2000 3775);
DISPLAY 1.234043 (2000 3775);
PAINT GREEN (2000 3775);
DISPLAY INVISIBLE (2000 3775);
FORCEPROP 1 LAST BODY_TYPE PLUMBING
J 2
(2325 3850);
DISPLAY 1.234043 (2325 3850);
PAINT GREEN (2325 3850);
DISPLAY INVISIBLE (2325 3850);
FORCEPROP 2 LAST CDS_LIB mstr_standard
J 0
(2325 3900);
DISPLAY 0.787234 (2325 3900);
PAINT MONO (2325 3900);
DISPLAY INVISIBLE (2325 3900);
FORCEADD OFFPAGE..1
(-2225 2200);
FORCEPROP 2 LAST $XR1 45 
J 0
(-2566 2200);
DISPLAY 0.638298 (-2566 2200);
PAINT MONO (-2566 2200);
FORCEPROP 2 LAST $XR0 24 
J 0
(-2476 2200);
DISPLAY 0.638298 (-2476 2200);
PAINT MONO (-2476 2200);
FORCEPROP 2 LAST PATH I16
J 0
(-2425 2250);
DISPLAY 1.021277 (-2425 2250);
PAINT ORANGE (-2425 2250);
DISPLAY INVISIBLE (-2425 2250);
FORCEPROP 1 LAST COMMENT_BODY TRUE
J 0
(-2100 2100);
DISPLAY 0.936170 (-2100 2100);
PAINT GREEN (-2100 2100);
DISPLAY INVISIBLE (-2100 2100);
FORCEPROP 1 LAST OFFPAGE TRUE
J 0
(-1900 2075);
DISPLAY 0.936170 (-1900 2075);
PAINT GREEN (-1900 2075);
DISPLAY INVISIBLE (-1900 2075);
FORCEPROP 2 LAST CDS_LIB mstr_standard
J 0
(-2225 2200);
DISPLAY 0.787234 (-2225 2200);
PAINT MONO (-2225 2200);
DISPLAY INVISIBLE (-2225 2200);
FORCEADD TAP..6
R 2
(2325 4100);
FORCEPROP 3 LASTPIN (2275 4100) SIG_NAME M_B_DQS_DP<10>
J 0
(2285 4110);
DISPLAY 0.659574 (2285 4110);
PAINT MONO (2285 4110);
DISPLAY INVISIBLE (2285 4110);
FORCEPROP 1 LASTPIN (2275 4100) BN 10
J 2
(2325 4110);
DISPLAY 0.617021 (2325 4110);
PAINT PINK (2325 4110);
FORCEPROP 1 LAST PATH I160
J 2
(2327 4100);
DISPLAY 0.872340 (2327 4100);
PAINT GREEN (2327 4100);
DISPLAY INVISIBLE (2327 4100);
FORCEPROP 1 LAST HDL_TAP TRUE
J 2
(2000 3975);
DISPLAY 1.234043 (2000 3975);
PAINT GREEN (2000 3975);
DISPLAY INVISIBLE (2000 3975);
FORCEPROP 1 LAST BODY_TYPE PLUMBING
J 2
(2325 4050);
DISPLAY 1.234043 (2325 4050);
PAINT GREEN (2325 4050);
DISPLAY INVISIBLE (2325 4050);
FORCEPROP 2 LAST CDS_LIB mstr_standard
J 0
(2325 4100);
DISPLAY 0.787234 (2325 4100);
PAINT MONO (2325 4100);
DISPLAY INVISIBLE (2325 4100);
FORCEADD TAP..6
R 2
(2325 4200);
FORCEPROP 3 LASTPIN (2275 4200) SIG_NAME M_B_DQS_DP<11>
J 0
(2285 4210);
DISPLAY 0.659574 (2285 4210);
PAINT MONO (2285 4210);
DISPLAY INVISIBLE (2285 4210);
FORCEPROP 1 LASTPIN (2275 4200) BN 11
J 2
(2325 4210);
DISPLAY 0.617021 (2325 4210);
PAINT PINK (2325 4210);
FORCEPROP 1 LAST PATH I161
J 2
(2327 4200);
DISPLAY 0.872340 (2327 4200);
PAINT GREEN (2327 4200);
DISPLAY INVISIBLE (2327 4200);
FORCEPROP 1 LAST HDL_TAP TRUE
J 2
(2000 4075);
DISPLAY 1.234043 (2000 4075);
PAINT GREEN (2000 4075);
DISPLAY INVISIBLE (2000 4075);
FORCEPROP 1 LAST BODY_TYPE PLUMBING
J 2
(2325 4150);
DISPLAY 1.234043 (2325 4150);
PAINT GREEN (2325 4150);
DISPLAY INVISIBLE (2325 4150);
FORCEPROP 2 LAST CDS_LIB mstr_standard
J 0
(2325 4200);
DISPLAY 0.787234 (2325 4200);
PAINT MONO (2325 4200);
DISPLAY INVISIBLE (2325 4200);
FORCEADD TAP..6
R 2
(2525 3950);
FORCEPROP 3 LASTPIN (2475 3950) SIG_NAME M_B_DQS_DN<9>
J 0
(2485 3960);
DISPLAY 0.659574 (2485 3960);
PAINT MONO (2485 3960);
DISPLAY INVISIBLE (2485 3960);
FORCEPROP 1 LASTPIN (2475 3950) BN 9
J 2
(2525 3960);
DISPLAY 0.617021 (2525 3960);
PAINT PINK (2525 3960);
FORCEPROP 1 LAST PATH I162
J 2
(2527 3950);
DISPLAY 0.872340 (2527 3950);
PAINT GREEN (2527 3950);
DISPLAY INVISIBLE (2527 3950);
FORCEPROP 1 LAST HDL_TAP TRUE
J 2
(2200 3825);
DISPLAY 1.234043 (2200 3825);
PAINT GREEN (2200 3825);
DISPLAY INVISIBLE (2200 3825);
FORCEPROP 1 LAST BODY_TYPE PLUMBING
J 2
(2525 3900);
DISPLAY 1.234043 (2525 3900);
PAINT GREEN (2525 3900);
DISPLAY INVISIBLE (2525 3900);
FORCEPROP 2 LAST CDS_LIB mstr_standard
J 0
(2525 3950);
DISPLAY 0.787234 (2525 3950);
PAINT MONO (2525 3950);
DISPLAY INVISIBLE (2525 3950);
FORCEADD TAP..6
R 2
(2525 3850);
FORCEPROP 3 LASTPIN (2475 3850) SIG_NAME M_B_DQS_DN<8>
J 0
(2485 3860);
DISPLAY 0.659574 (2485 3860);
PAINT MONO (2485 3860);
DISPLAY INVISIBLE (2485 3860);
FORCEPROP 1 LASTPIN (2475 3850) BN 8
J 2
(2525 3860);
DISPLAY 0.617021 (2525 3860);
PAINT PINK (2525 3860);
FORCEPROP 1 LAST PATH I163
J 2
(2527 3850);
DISPLAY 0.872340 (2527 3850);
PAINT GREEN (2527 3850);
DISPLAY INVISIBLE (2527 3850);
FORCEPROP 1 LAST HDL_TAP TRUE
J 2
(2200 3725);
DISPLAY 1.234043 (2200 3725);
PAINT GREEN (2200 3725);
DISPLAY INVISIBLE (2200 3725);
FORCEPROP 1 LAST BODY_TYPE PLUMBING
J 2
(2525 3800);
DISPLAY 1.234043 (2525 3800);
PAINT GREEN (2525 3800);
DISPLAY INVISIBLE (2525 3800);
FORCEPROP 2 LAST CDS_LIB mstr_standard
J 0
(2525 3850);
DISPLAY 0.787234 (2525 3850);
PAINT MONO (2525 3850);
DISPLAY INVISIBLE (2525 3850);
FORCEADD TAP..6
R 2
(2525 3750);
FORCEPROP 3 LASTPIN (2475 3750) SIG_NAME M_B_DQS_DN<7>
J 0
(2485 3760);
DISPLAY 0.659574 (2485 3760);
PAINT MONO (2485 3760);
DISPLAY INVISIBLE (2485 3760);
FORCEPROP 1 LASTPIN (2475 3750) BN 7
J 2
(2525 3760);
DISPLAY 0.617021 (2525 3760);
PAINT PINK (2525 3760);
FORCEPROP 1 LAST PATH I164
J 2
(2527 3750);
DISPLAY 0.872340 (2527 3750);
PAINT GREEN (2527 3750);
DISPLAY INVISIBLE (2527 3750);
FORCEPROP 1 LAST HDL_TAP TRUE
J 2
(2200 3625);
DISPLAY 1.234043 (2200 3625);
PAINT GREEN (2200 3625);
DISPLAY INVISIBLE (2200 3625);
FORCEPROP 1 LAST BODY_TYPE PLUMBING
J 2
(2525 3700);
DISPLAY 1.234043 (2525 3700);
PAINT GREEN (2525 3700);
DISPLAY INVISIBLE (2525 3700);
FORCEPROP 2 LAST CDS_LIB mstr_standard
J 0
(2525 3750);
DISPLAY 0.787234 (2525 3750);
PAINT MONO (2525 3750);
DISPLAY INVISIBLE (2525 3750);
FORCEADD TAP..6
R 2
(2525 4250);
FORCEPROP 3 LASTPIN (2475 4250) SIG_NAME M_B_DQS_DN<12>
J 0
(2485 4260);
DISPLAY 0.659574 (2485 4260);
PAINT MONO (2485 4260);
DISPLAY INVISIBLE (2485 4260);
FORCEPROP 1 LASTPIN (2475 4250) BN 12
J 2
(2525 4260);
DISPLAY 0.617021 (2525 4260);
PAINT PINK (2525 4260);
FORCEPROP 1 LAST PATH I165
J 2
(2527 4250);
DISPLAY 0.872340 (2527 4250);
PAINT GREEN (2527 4250);
DISPLAY INVISIBLE (2527 4250);
FORCEPROP 1 LAST HDL_TAP TRUE
J 2
(2200 4125);
DISPLAY 1.234043 (2200 4125);
PAINT GREEN (2200 4125);
DISPLAY INVISIBLE (2200 4125);
FORCEPROP 1 LAST BODY_TYPE PLUMBING
J 2
(2525 4200);
DISPLAY 1.234043 (2525 4200);
PAINT GREEN (2525 4200);
DISPLAY INVISIBLE (2525 4200);
FORCEPROP 2 LAST CDS_LIB mstr_standard
J 0
(2525 4250);
DISPLAY 0.787234 (2525 4250);
PAINT MONO (2525 4250);
DISPLAY INVISIBLE (2525 4250);
FORCEADD TAP..6
R 2
(2525 4050);
FORCEPROP 3 LASTPIN (2475 4050) SIG_NAME M_B_DQS_DN<10>
J 0
(2485 4060);
DISPLAY 0.659574 (2485 4060);
PAINT MONO (2485 4060);
DISPLAY INVISIBLE (2485 4060);
FORCEPROP 1 LASTPIN (2475 4050) BN 10
J 2
(2525 4060);
DISPLAY 0.617021 (2525 4060);
PAINT PINK (2525 4060);
FORCEPROP 1 LAST PATH I166
J 2
(2527 4050);
DISPLAY 0.872340 (2527 4050);
PAINT GREEN (2527 4050);
DISPLAY INVISIBLE (2527 4050);
FORCEPROP 1 LAST HDL_TAP TRUE
J 2
(2200 3925);
DISPLAY 1.234043 (2200 3925);
PAINT GREEN (2200 3925);
DISPLAY INVISIBLE (2200 3925);
FORCEPROP 1 LAST BODY_TYPE PLUMBING
J 2
(2525 4000);
DISPLAY 1.234043 (2525 4000);
PAINT GREEN (2525 4000);
DISPLAY INVISIBLE (2525 4000);
FORCEPROP 2 LAST CDS_LIB mstr_standard
J 0
(2525 4050);
DISPLAY 0.787234 (2525 4050);
PAINT MONO (2525 4050);
DISPLAY INVISIBLE (2525 4050);
FORCEADD TAP..6
R 2
(2525 4150);
FORCEPROP 3 LASTPIN (2475 4150) SIG_NAME M_B_DQS_DN<11>
J 0
(2485 4160);
DISPLAY 0.659574 (2485 4160);
PAINT MONO (2485 4160);
DISPLAY INVISIBLE (2485 4160);
FORCEPROP 1 LASTPIN (2475 4150) BN 11
J 2
(2525 4160);
DISPLAY 0.617021 (2525 4160);
PAINT PINK (2525 4160);
FORCEPROP 1 LAST PATH I167
J 2
(2527 4150);
DISPLAY 0.872340 (2527 4150);
PAINT GREEN (2527 4150);
DISPLAY INVISIBLE (2527 4150);
FORCEPROP 1 LAST HDL_TAP TRUE
J 2
(2200 4025);
DISPLAY 1.234043 (2200 4025);
PAINT GREEN (2200 4025);
DISPLAY INVISIBLE (2200 4025);
FORCEPROP 1 LAST BODY_TYPE PLUMBING
J 2
(2525 4100);
DISPLAY 1.234043 (2525 4100);
PAINT GREEN (2525 4100);
DISPLAY INVISIBLE (2525 4100);
FORCEPROP 2 LAST CDS_LIB mstr_standard
J 0
(2525 4150);
DISPLAY 0.787234 (2525 4150);
PAINT MONO (2525 4150);
DISPLAY INVISIBLE (2525 4150);
FORCEADD TAP..6
R 2
(2325 4300);
FORCEPROP 3 LASTPIN (2275 4300) SIG_NAME M_B_DQS_DP<12>
J 0
(2285 4310);
DISPLAY 0.659574 (2285 4310);
PAINT MONO (2285 4310);
DISPLAY INVISIBLE (2285 4310);
FORCEPROP 1 LASTPIN (2275 4300) BN 12
J 2
(2325 4310);
DISPLAY 0.617021 (2325 4310);
PAINT PINK (2325 4310);
FORCEPROP 1 LAST PATH I168
J 2
(2327 4300);
DISPLAY 0.872340 (2327 4300);
PAINT GREEN (2327 4300);
DISPLAY INVISIBLE (2327 4300);
FORCEPROP 1 LAST HDL_TAP TRUE
J 2
(2000 4175);
DISPLAY 1.234043 (2000 4175);
PAINT GREEN (2000 4175);
DISPLAY INVISIBLE (2000 4175);
FORCEPROP 1 LAST BODY_TYPE PLUMBING
J 2
(2325 4250);
DISPLAY 1.234043 (2325 4250);
PAINT GREEN (2325 4250);
DISPLAY INVISIBLE (2325 4250);
FORCEPROP 2 LAST CDS_LIB mstr_standard
J 0
(2325 4300);
DISPLAY 0.787234 (2325 4300);
PAINT MONO (2325 4300);
DISPLAY INVISIBLE (2325 4300);
FORCEADD TAP..6
R 2
(2325 4500);
FORCEPROP 3 LASTPIN (2275 4500) SIG_NAME M_B_DQS_DP<14>
J 0
(2285 4510);
DISPLAY 0.659574 (2285 4510);
PAINT MONO (2285 4510);
DISPLAY INVISIBLE (2285 4510);
FORCEPROP 1 LASTPIN (2275 4500) BN 14
J 2
(2325 4510);
DISPLAY 0.617021 (2325 4510);
PAINT PINK (2325 4510);
FORCEPROP 1 LAST PATH I169
J 2
(2327 4500);
DISPLAY 0.872340 (2327 4500);
PAINT GREEN (2327 4500);
DISPLAY INVISIBLE (2327 4500);
FORCEPROP 1 LAST HDL_TAP TRUE
J 2
(2000 4375);
DISPLAY 1.234043 (2000 4375);
PAINT GREEN (2000 4375);
DISPLAY INVISIBLE (2000 4375);
FORCEPROP 1 LAST BODY_TYPE PLUMBING
J 2
(2325 4450);
DISPLAY 1.234043 (2325 4450);
PAINT GREEN (2325 4450);
DISPLAY INVISIBLE (2325 4450);
FORCEPROP 2 LAST CDS_LIB mstr_standard
J 0
(2325 4500);
DISPLAY 0.787234 (2325 4500);
PAINT MONO (2325 4500);
DISPLAY INVISIBLE (2325 4500);
FORCEADD OFFPAGE..6
(-2225 2250);
FORCEPROP 2 LAST $XR1 45 
J 0
(-2564 2250);
DISPLAY 0.638298 (-2564 2250);
PAINT MONO (-2564 2250);
FORCEPROP 2 LAST $XR0 24 
J 0
(-2474 2250);
DISPLAY 0.638298 (-2474 2250);
PAINT MONO (-2474 2250);
FORCEPROP 2 LAST PATH I17
J 0
(-2425 2300);
DISPLAY 1.021277 (-2425 2300);
PAINT ORANGE (-2425 2300);
DISPLAY INVISIBLE (-2425 2300);
FORCEPROP 1 LAST COMMENT_BODY TRUE
J 0
(-2125 2175);
DISPLAY 0.936170 (-2125 2175);
PAINT GREEN (-2125 2175);
DISPLAY INVISIBLE (-2125 2175);
FORCEPROP 1 LAST OFFPAGE TRUE
J 0
(-1900 2125);
DISPLAY 0.936170 (-1900 2125);
PAINT GREEN (-1900 2125);
DISPLAY INVISIBLE (-1900 2125);
FORCEPROP 2 LAST CDS_LIB mstr_standard
J 0
(-2225 2250);
DISPLAY 0.787234 (-2225 2250);
PAINT MONO (-2225 2250);
DISPLAY INVISIBLE (-2225 2250);
FORCEADD TAP..6
R 2
(2325 4400);
FORCEPROP 3 LASTPIN (2275 4400) SIG_NAME M_B_DQS_DP<13>
J 0
(2285 4410);
DISPLAY 0.659574 (2285 4410);
PAINT MONO (2285 4410);
DISPLAY INVISIBLE (2285 4410);
FORCEPROP 1 LASTPIN (2275 4400) BN 13
J 2
(2325 4410);
DISPLAY 0.617021 (2325 4410);
PAINT PINK (2325 4410);
FORCEPROP 1 LAST PATH I170
J 2
(2327 4400);
DISPLAY 0.872340 (2327 4400);
PAINT GREEN (2327 4400);
DISPLAY INVISIBLE (2327 4400);
FORCEPROP 1 LAST HDL_TAP TRUE
J 2
(2000 4275);
DISPLAY 1.234043 (2000 4275);
PAINT GREEN (2000 4275);
DISPLAY INVISIBLE (2000 4275);
FORCEPROP 1 LAST BODY_TYPE PLUMBING
J 2
(2325 4350);
DISPLAY 1.234043 (2325 4350);
PAINT GREEN (2325 4350);
DISPLAY INVISIBLE (2325 4350);
FORCEPROP 2 LAST CDS_LIB mstr_standard
J 0
(2325 4400);
DISPLAY 0.787234 (2325 4400);
PAINT MONO (2325 4400);
DISPLAY INVISIBLE (2325 4400);
FORCEADD TAP..6
R 2
(2325 4600);
FORCEPROP 3 LASTPIN (2275 4600) SIG_NAME M_B_DQS_DP<15>
J 0
(2285 4610);
DISPLAY 0.659574 (2285 4610);
PAINT MONO (2285 4610);
DISPLAY INVISIBLE (2285 4610);
FORCEPROP 1 LASTPIN (2275 4600) BN 15
J 2
(2325 4610);
DISPLAY 0.617021 (2325 4610);
PAINT PINK (2325 4610);
FORCEPROP 1 LAST PATH I171
J 2
(2327 4600);
DISPLAY 0.872340 (2327 4600);
PAINT GREEN (2327 4600);
DISPLAY INVISIBLE (2327 4600);
FORCEPROP 1 LAST HDL_TAP TRUE
J 2
(2000 4475);
DISPLAY 1.234043 (2000 4475);
PAINT GREEN (2000 4475);
DISPLAY INVISIBLE (2000 4475);
FORCEPROP 1 LAST BODY_TYPE PLUMBING
J 2
(2325 4550);
DISPLAY 1.234043 (2325 4550);
PAINT GREEN (2325 4550);
DISPLAY INVISIBLE (2325 4550);
FORCEPROP 2 LAST CDS_LIB mstr_standard
J 0
(2325 4600);
DISPLAY 0.787234 (2325 4600);
PAINT MONO (2325 4600);
DISPLAY INVISIBLE (2325 4600);
FORCEADD TAP..6
R 2
(2325 4700);
FORCEPROP 3 LASTPIN (2275 4700) SIG_NAME M_B_DQS_DP<16>
J 0
(2285 4710);
DISPLAY 0.659574 (2285 4710);
PAINT MONO (2285 4710);
DISPLAY INVISIBLE (2285 4710);
FORCEPROP 1 LASTPIN (2275 4700) BN 16
J 2
(2325 4710);
DISPLAY 0.617021 (2325 4710);
PAINT PINK (2325 4710);
FORCEPROP 1 LAST PATH I172
J 2
(2327 4700);
DISPLAY 0.872340 (2327 4700);
PAINT GREEN (2327 4700);
DISPLAY INVISIBLE (2327 4700);
FORCEPROP 1 LAST HDL_TAP TRUE
J 2
(2000 4575);
DISPLAY 1.234043 (2000 4575);
PAINT GREEN (2000 4575);
DISPLAY INVISIBLE (2000 4575);
FORCEPROP 1 LAST BODY_TYPE PLUMBING
J 2
(2325 4650);
DISPLAY 1.234043 (2325 4650);
PAINT GREEN (2325 4650);
DISPLAY INVISIBLE (2325 4650);
FORCEPROP 2 LAST CDS_LIB mstr_standard
J 0
(2325 4700);
DISPLAY 0.787234 (2325 4700);
PAINT MONO (2325 4700);
DISPLAY INVISIBLE (2325 4700);
FORCEADD TAP..6
R 2
(2525 4350);
FORCEPROP 3 LASTPIN (2475 4350) SIG_NAME M_B_DQS_DN<13>
J 0
(2485 4360);
DISPLAY 0.659574 (2485 4360);
PAINT MONO (2485 4360);
DISPLAY INVISIBLE (2485 4360);
FORCEPROP 1 LASTPIN (2475 4350) BN 13
J 2
(2525 4360);
DISPLAY 0.617021 (2525 4360);
PAINT PINK (2525 4360);
FORCEPROP 1 LAST PATH I173
J 2
(2527 4350);
DISPLAY 0.872340 (2527 4350);
PAINT GREEN (2527 4350);
DISPLAY INVISIBLE (2527 4350);
FORCEPROP 1 LAST HDL_TAP TRUE
J 2
(2200 4225);
DISPLAY 1.234043 (2200 4225);
PAINT GREEN (2200 4225);
DISPLAY INVISIBLE (2200 4225);
FORCEPROP 1 LAST BODY_TYPE PLUMBING
J 2
(2525 4300);
DISPLAY 1.234043 (2525 4300);
PAINT GREEN (2525 4300);
DISPLAY INVISIBLE (2525 4300);
FORCEPROP 2 LAST CDS_LIB mstr_standard
J 0
(2525 4350);
DISPLAY 0.787234 (2525 4350);
PAINT MONO (2525 4350);
DISPLAY INVISIBLE (2525 4350);
FORCEADD TAP..6
R 2
(2525 4450);
FORCEPROP 3 LASTPIN (2475 4450) SIG_NAME M_B_DQS_DN<14>
J 0
(2485 4460);
DISPLAY 0.659574 (2485 4460);
PAINT MONO (2485 4460);
DISPLAY INVISIBLE (2485 4460);
FORCEPROP 1 LASTPIN (2475 4450) BN 14
J 2
(2525 4460);
DISPLAY 0.617021 (2525 4460);
PAINT PINK (2525 4460);
FORCEPROP 1 LAST PATH I174
J 2
(2527 4450);
DISPLAY 0.872340 (2527 4450);
PAINT GREEN (2527 4450);
DISPLAY INVISIBLE (2527 4450);
FORCEPROP 1 LAST HDL_TAP TRUE
J 2
(2200 4325);
DISPLAY 1.234043 (2200 4325);
PAINT GREEN (2200 4325);
DISPLAY INVISIBLE (2200 4325);
FORCEPROP 1 LAST BODY_TYPE PLUMBING
J 2
(2525 4400);
DISPLAY 1.234043 (2525 4400);
PAINT GREEN (2525 4400);
DISPLAY INVISIBLE (2525 4400);
FORCEPROP 2 LAST CDS_LIB mstr_standard
J 0
(2525 4450);
DISPLAY 0.787234 (2525 4450);
PAINT MONO (2525 4450);
DISPLAY INVISIBLE (2525 4450);
FORCEADD TAP..6
R 2
(2525 4750);
FORCEPROP 3 LASTPIN (2475 4750) SIG_NAME M_B_DQS_DN<17>
J 0
(2485 4760);
DISPLAY 0.659574 (2485 4760);
PAINT MONO (2485 4760);
DISPLAY INVISIBLE (2485 4760);
FORCEPROP 1 LASTPIN (2475 4750) BN 17
J 2
(2525 4760);
DISPLAY 0.617021 (2525 4760);
PAINT PINK (2525 4760);
FORCEPROP 1 LAST PATH I175
J 2
(2527 4750);
DISPLAY 0.872340 (2527 4750);
PAINT GREEN (2527 4750);
DISPLAY INVISIBLE (2527 4750);
FORCEPROP 1 LAST HDL_TAP TRUE
J 2
(2200 4625);
DISPLAY 1.234043 (2200 4625);
PAINT GREEN (2200 4625);
DISPLAY INVISIBLE (2200 4625);
FORCEPROP 1 LAST BODY_TYPE PLUMBING
J 2
(2525 4700);
DISPLAY 1.234043 (2525 4700);
PAINT GREEN (2525 4700);
DISPLAY INVISIBLE (2525 4700);
FORCEPROP 2 LAST CDS_LIB mstr_standard
J 2
(2525 4750);
DISPLAY 0.787234 (2525 4750);
PAINT MONO (2525 4750);
DISPLAY INVISIBLE (2525 4750);
FORCEADD TAP..6
R 2
(2525 4550);
FORCEPROP 3 LASTPIN (2475 4550) SIG_NAME M_B_DQS_DN<15>
J 0
(2485 4560);
DISPLAY 0.659574 (2485 4560);
PAINT MONO (2485 4560);
DISPLAY INVISIBLE (2485 4560);
FORCEPROP 1 LASTPIN (2475 4550) BN 15
J 2
(2525 4560);
DISPLAY 0.617021 (2525 4560);
PAINT PINK (2525 4560);
FORCEPROP 1 LAST PATH I176
J 2
(2527 4550);
DISPLAY 0.872340 (2527 4550);
PAINT GREEN (2527 4550);
DISPLAY INVISIBLE (2527 4550);
FORCEPROP 1 LAST HDL_TAP TRUE
J 2
(2200 4425);
DISPLAY 1.234043 (2200 4425);
PAINT GREEN (2200 4425);
DISPLAY INVISIBLE (2200 4425);
FORCEPROP 1 LAST BODY_TYPE PLUMBING
J 2
(2525 4500);
DISPLAY 1.234043 (2525 4500);
PAINT GREEN (2525 4500);
DISPLAY INVISIBLE (2525 4500);
FORCEPROP 2 LAST CDS_LIB mstr_standard
J 0
(2525 4550);
DISPLAY 0.787234 (2525 4550);
PAINT MONO (2525 4550);
DISPLAY INVISIBLE (2525 4550);
FORCEADD TAP..6
R 2
(2525 4650);
FORCEPROP 3 LASTPIN (2475 4650) SIG_NAME M_B_DQS_DN<16>
J 0
(2485 4660);
DISPLAY 0.659574 (2485 4660);
PAINT MONO (2485 4660);
DISPLAY INVISIBLE (2485 4660);
FORCEPROP 1 LASTPIN (2475 4650) BN 16
J 2
(2525 4660);
DISPLAY 0.617021 (2525 4660);
PAINT PINK (2525 4660);
FORCEPROP 1 LAST PATH I177
J 2
(2527 4650);
DISPLAY 0.872340 (2527 4650);
PAINT GREEN (2527 4650);
DISPLAY INVISIBLE (2527 4650);
FORCEPROP 1 LAST HDL_TAP TRUE
J 2
(2200 4525);
DISPLAY 1.234043 (2200 4525);
PAINT GREEN (2200 4525);
DISPLAY INVISIBLE (2200 4525);
FORCEPROP 1 LAST BODY_TYPE PLUMBING
J 2
(2525 4600);
DISPLAY 1.234043 (2525 4600);
PAINT GREEN (2525 4600);
DISPLAY INVISIBLE (2525 4600);
FORCEPROP 2 LAST CDS_LIB mstr_standard
J 0
(2525 4650);
DISPLAY 0.787234 (2525 4650);
PAINT MONO (2525 4650);
DISPLAY INVISIBLE (2525 4650);
FORCEADD TAP..6
R 2
(2325 4800);
FORCEPROP 3 LASTPIN (2275 4800) SIG_NAME M_B_DQS_DP<17>
J 0
(2285 4810);
DISPLAY 0.659574 (2285 4810);
PAINT MONO (2285 4810);
DISPLAY INVISIBLE (2285 4810);
FORCEPROP 1 LASTPIN (2275 4800) BN 17
J 2
(2325 4810);
DISPLAY 0.617021 (2325 4810);
PAINT PINK (2325 4810);
FORCEPROP 1 LAST PATH I178
J 2
(2327 4800);
DISPLAY 0.872340 (2327 4800);
PAINT GREEN (2327 4800);
DISPLAY INVISIBLE (2327 4800);
FORCEPROP 1 LAST HDL_TAP TRUE
J 2
(2000 4675);
DISPLAY 1.234043 (2000 4675);
PAINT GREEN (2000 4675);
DISPLAY INVISIBLE (2000 4675);
FORCEPROP 1 LAST BODY_TYPE PLUMBING
J 2
(2325 4750);
DISPLAY 1.234043 (2325 4750);
PAINT GREEN (2325 4750);
DISPLAY INVISIBLE (2325 4750);
FORCEPROP 2 LAST CDS_LIB mstr_standard
J 2
(2325 4800);
DISPLAY 0.787234 (2325 4800);
PAINT MONO (2325 4800);
DISPLAY INVISIBLE (2325 4800);
FORCEADD OFFPAGE..3
(3225 4800);
FORCEPROP 2 LAST $XR1 45 
J 0
(3529 4800);
DISPLAY 0.638298 (3529 4800);
PAINT MONO (3529 4800);
FORCEPROP 2 LAST $XR0 24 
J 0
(3439 4800);
DISPLAY 0.638298 (3439 4800);
PAINT MONO (3439 4800);
FORCEPROP 2 LAST PATH I179
J 0
(3450 4850);
DISPLAY 1.021277 (3450 4850);
PAINT ORANGE (3450 4850);
DISPLAY INVISIBLE (3450 4850);
FORCEPROP 1 LAST COMMENT_BODY TRUE
J 0
(3175 4700);
DISPLAY 0.936170 (3175 4700);
PAINT GREEN (3175 4700);
DISPLAY INVISIBLE (3175 4700);
FORCEPROP 1 LAST OFFPAGE TRUE
J 0
(3550 4675);
DISPLAY 0.936170 (3550 4675);
PAINT GREEN (3550 4675);
DISPLAY INVISIBLE (3550 4675);
FORCEPROP 2 LAST CDS_LIB mstr_standard
J 0
(3225 4800);
DISPLAY 0.787234 (3225 4800);
PAINT MONO (3225 4800);
DISPLAY INVISIBLE (3225 4800);
FORCEADD OFFPAGE..1
(-2225 2450);
FORCEPROP 2 LAST $XR1 45 
J 0
(-2566 2450);
DISPLAY 0.638298 (-2566 2450);
PAINT MONO (-2566 2450);
FORCEPROP 2 LAST $XR0 24 
J 0
(-2476 2450);
DISPLAY 0.638298 (-2476 2450);
PAINT MONO (-2476 2450);
FORCEPROP 2 LAST PATH I18
J 0
(-2425 2500);
DISPLAY 1.021277 (-2425 2500);
PAINT ORANGE (-2425 2500);
DISPLAY INVISIBLE (-2425 2500);
FORCEPROP 1 LAST COMMENT_BODY TRUE
J 0
(-2100 2350);
DISPLAY 0.936170 (-2100 2350);
PAINT GREEN (-2100 2350);
DISPLAY INVISIBLE (-2100 2350);
FORCEPROP 1 LAST OFFPAGE TRUE
J 0
(-1900 2325);
DISPLAY 0.936170 (-1900 2325);
PAINT GREEN (-1900 2325);
DISPLAY INVISIBLE (-1900 2325);
FORCEPROP 2 LAST CDS_LIB mstr_standard
J 0
(-2225 2450);
DISPLAY 0.787234 (-2225 2450);
PAINT MONO (-2225 2450);
DISPLAY INVISIBLE (-2225 2450);
FORCEADD OFFPAGE..3
(3225 4850);
FORCEPROP 2 LAST $XR1 45 
J 0
(3529 4850);
DISPLAY 0.638298 (3529 4850);
PAINT MONO (3529 4850);
FORCEPROP 2 LAST $XR0 24 
J 0
(3439 4850);
DISPLAY 0.638298 (3439 4850);
PAINT MONO (3439 4850);
FORCEPROP 2 LAST PATH I180
J 0
(3450 4900);
DISPLAY 1.021277 (3450 4900);
PAINT ORANGE (3450 4900);
DISPLAY INVISIBLE (3450 4900);
FORCEPROP 1 LAST COMMENT_BODY TRUE
J 0
(3175 4750);
DISPLAY 0.936170 (3175 4750);
PAINT GREEN (3175 4750);
DISPLAY INVISIBLE (3175 4750);
FORCEPROP 1 LAST OFFPAGE TRUE
J 0
(3550 4725);
DISPLAY 0.936170 (3550 4725);
PAINT GREEN (3550 4725);
DISPLAY INVISIBLE (3550 4725);
FORCEPROP 2 LAST CDS_LIB mstr_standard
J 0
(3225 4850);
DISPLAY 0.787234 (3225 4850);
PAINT MONO (3225 4850);
DISPLAY INVISIBLE (3225 4850);
FORCEADD P12V_NVDIMM_ABC..1
(2375 2725);
FORCEPROP 3 LASTPIN (2375 2675) SIG_NAME P12V_NVDIMM_ABC\g
J 0
(2385 2685);
DISPLAY 0.659574 (2385 2685);
PAINT MONO (2385 2685);
DISPLAY INVISIBLE (2385 2685);
FORCEPROP 1 LAST HDL_POWER P12V_NVDIMM_ABC
J 1
(2375 2750);
DISPLAY 0.872340 (2375 2750);
PAINT GREEN (2375 2750);
DISPLAY INVISIBLE (2375 2750);
FORCEPROP 1 LAST PATH I181
J 0
(2425 2750);
DISPLAY 0.872340 (2425 2750);
PAINT AQUA (2425 2750);
DISPLAY INVISIBLE (2425 2750);
FORCEPROP 1 LAST BODY_TYPE PLUMBING
J 0
(2330 2682);
DISPLAY 0.340426 (2330 2682);
PAINT GREEN (2330 2682);
DISPLAY INVISIBLE (2330 2682);
FORCEPROP 2 LAST CDS_LIB mstr_symbols
J 0
(2375 2725);
PAINT ORANGE (2375 2725);
DISPLAY INVISIBLE (2375 2725);
FORCEPROP 1 LAST VOLTAGE 12.0
J 0
(2330 2682);
DISPLAY 0.340426 (2330 2682);
PAINT SKYBLUE (2330 2682);
DISPLAY INVISIBLE (2330 2682);
FORCEADD OFFPAGE..1
(-2225 2600);
FORCEPROP 2 LAST $XR1 45 
J 0
(-2566 2600);
DISPLAY 0.638298 (-2566 2600);
PAINT MONO (-2566 2600);
FORCEPROP 2 LAST $XR0 24 
J 0
(-2476 2600);
DISPLAY 0.638298 (-2476 2600);
PAINT MONO (-2476 2600);
FORCEPROP 2 LAST PATH I19
J 0
(-2425 2650);
DISPLAY 1.021277 (-2425 2650);
PAINT ORANGE (-2425 2650);
DISPLAY INVISIBLE (-2425 2650);
FORCEPROP 1 LAST COMMENT_BODY TRUE
J 0
(-2100 2500);
DISPLAY 0.936170 (-2100 2500);
PAINT GREEN (-2100 2500);
DISPLAY INVISIBLE (-2100 2500);
FORCEPROP 1 LAST OFFPAGE TRUE
J 0
(-1900 2475);
DISPLAY 0.936170 (-1900 2475);
PAINT GREEN (-1900 2475);
DISPLAY INVISIBLE (-1900 2475);
FORCEPROP 2 LAST CDS_LIB mstr_standard
J 0
(-2225 2600);
DISPLAY 0.787234 (-2225 2600);
PAINT MONO (-2225 2600);
DISPLAY INVISIBLE (-2225 2600);
FORCEADD OFFPAGE..1
(-3125 1100);
FORCEPROP 2 LAST $XR1 45 
J 0
(-3436 1100);
DISPLAY 0.638298 (-3436 1100);
PAINT MONO (-3436 1100);
FORCEPROP 2 LAST $XR0 98 
J 0
(-3346 1100);
DISPLAY 0.638298 (-3346 1100);
PAINT MONO (-3346 1100);
FORCEPROP 2 LAST PATH I2
J 0
(-3325 1150);
DISPLAY 1.021277 (-3325 1150);
PAINT ORANGE (-3325 1150);
DISPLAY INVISIBLE (-3325 1150);
FORCEPROP 1 LAST COMMENT_BODY TRUE
J 0
(-3000 1000);
DISPLAY 0.936170 (-3000 1000);
PAINT GREEN (-3000 1000);
DISPLAY INVISIBLE (-3000 1000);
FORCEPROP 1 LAST OFFPAGE TRUE
J 0
(-2800 975);
DISPLAY 0.936170 (-2800 975);
PAINT GREEN (-2800 975);
DISPLAY INVISIBLE (-2800 975);
FORCEPROP 2 LAST CDS_LIB mstr_standard
J 0
(-3125 1100);
DISPLAY 0.787234 (-3125 1100);
PAINT MONO (-3125 1100);
DISPLAY INVISIBLE (-3125 1100);
FORCEADD TAP..6
(-1575 1900);
FORCEPROP 3 LASTPIN (-1525 1900) SIG_NAME M_B_ECC<1>
J 0
(-1515 1910);
DISPLAY 0.659574 (-1515 1910);
PAINT MONO (-1515 1910);
DISPLAY INVISIBLE (-1515 1910);
FORCEPROP 1 LASTPIN (-1525 1900) BN 1
J 0
(-1575 1910);
DISPLAY 0.617021 (-1575 1910);
PAINT PINK (-1575 1910);
FORCEPROP 1 LAST PATH I20
J 0
(-1577 1900);
DISPLAY 0.872340 (-1577 1900);
PAINT GREEN (-1577 1900);
DISPLAY INVISIBLE (-1577 1900);
FORCEPROP 1 LAST HDL_TAP TRUE
J 0
(-1250 1775);
DISPLAY 1.234043 (-1250 1775);
PAINT GREEN (-1250 1775);
DISPLAY INVISIBLE (-1250 1775);
FORCEPROP 1 LAST BODY_TYPE PLUMBING
J 0
(-1575 1850);
DISPLAY 1.234043 (-1575 1850);
PAINT GREEN (-1575 1850);
DISPLAY INVISIBLE (-1575 1850);
FORCEPROP 2 LAST CDS_LIB mstr_standard
J 0
(-1575 1900);
DISPLAY 0.787234 (-1575 1900);
PAINT MONO (-1575 1900);
DISPLAY INVISIBLE (-1575 1900);
FORCEADD TAP..6
(-1575 1850);
FORCEPROP 3 LASTPIN (-1525 1850) SIG_NAME M_B_ECC<0>
J 0
(-1515 1860);
DISPLAY 0.659574 (-1515 1860);
PAINT MONO (-1515 1860);
DISPLAY INVISIBLE (-1515 1860);
FORCEPROP 1 LASTPIN (-1525 1850) BN 0
J 0
(-1575 1860);
DISPLAY 0.617021 (-1575 1860);
PAINT PINK (-1575 1860);
FORCEPROP 1 LAST PATH I21
J 0
(-1577 1850);
DISPLAY 0.872340 (-1577 1850);
PAINT GREEN (-1577 1850);
DISPLAY INVISIBLE (-1577 1850);
FORCEPROP 1 LAST HDL_TAP TRUE
J 0
(-1250 1725);
DISPLAY 1.234043 (-1250 1725);
PAINT GREEN (-1250 1725);
DISPLAY INVISIBLE (-1250 1725);
FORCEPROP 1 LAST BODY_TYPE PLUMBING
J 0
(-1575 1800);
DISPLAY 1.234043 (-1575 1800);
PAINT GREEN (-1575 1800);
DISPLAY INVISIBLE (-1575 1800);
FORCEPROP 2 LAST CDS_LIB mstr_standard
J 0
(-1575 1850);
DISPLAY 0.787234 (-1575 1850);
PAINT MONO (-1575 1850);
DISPLAY INVISIBLE (-1575 1850);
FORCEADD TAP..6
(-1575 1950);
FORCEPROP 3 LASTPIN (-1525 1950) SIG_NAME M_B_ECC<2>
J 0
(-1515 1960);
DISPLAY 0.659574 (-1515 1960);
PAINT MONO (-1515 1960);
DISPLAY INVISIBLE (-1515 1960);
FORCEPROP 1 LASTPIN (-1525 1950) BN 2
J 0
(-1575 1960);
DISPLAY 0.617021 (-1575 1960);
PAINT PINK (-1575 1960);
FORCEPROP 1 LAST PATH I22
J 0
(-1577 1950);
DISPLAY 0.872340 (-1577 1950);
PAINT GREEN (-1577 1950);
DISPLAY INVISIBLE (-1577 1950);
FORCEPROP 1 LAST HDL_TAP TRUE
J 0
(-1250 1825);
DISPLAY 1.234043 (-1250 1825);
PAINT GREEN (-1250 1825);
DISPLAY INVISIBLE (-1250 1825);
FORCEPROP 1 LAST BODY_TYPE PLUMBING
J 0
(-1575 1900);
DISPLAY 1.234043 (-1575 1900);
PAINT GREEN (-1575 1900);
DISPLAY INVISIBLE (-1575 1900);
FORCEPROP 2 LAST CDS_LIB mstr_standard
J 0
(-1575 1950);
DISPLAY 0.787234 (-1575 1950);
PAINT MONO (-1575 1950);
DISPLAY INVISIBLE (-1575 1950);
FORCEADD TAP..6
(-1575 2000);
FORCEPROP 3 LASTPIN (-1525 2000) SIG_NAME M_B_ECC<3>
J 0
(-1515 2010);
DISPLAY 0.659574 (-1515 2010);
PAINT MONO (-1515 2010);
DISPLAY INVISIBLE (-1515 2010);
FORCEPROP 1 LASTPIN (-1525 2000) BN 3
J 0
(-1575 2010);
DISPLAY 0.617021 (-1575 2010);
PAINT PINK (-1575 2010);
FORCEPROP 1 LAST PATH I23
J 0
(-1577 2000);
DISPLAY 0.872340 (-1577 2000);
PAINT GREEN (-1577 2000);
DISPLAY INVISIBLE (-1577 2000);
FORCEPROP 1 LAST HDL_TAP TRUE
J 0
(-1250 1875);
DISPLAY 1.234043 (-1250 1875);
PAINT GREEN (-1250 1875);
DISPLAY INVISIBLE (-1250 1875);
FORCEPROP 1 LAST BODY_TYPE PLUMBING
J 0
(-1575 1950);
DISPLAY 1.234043 (-1575 1950);
PAINT GREEN (-1575 1950);
DISPLAY INVISIBLE (-1575 1950);
FORCEPROP 2 LAST CDS_LIB mstr_standard
J 0
(-1575 2000);
DISPLAY 0.787234 (-1575 2000);
PAINT MONO (-1575 2000);
DISPLAY INVISIBLE (-1575 2000);
FORCEADD TAP..6
(-1575 2050);
FORCEPROP 3 LASTPIN (-1525 2050) SIG_NAME M_B_ECC<4>
J 0
(-1515 2060);
DISPLAY 0.659574 (-1515 2060);
PAINT MONO (-1515 2060);
DISPLAY INVISIBLE (-1515 2060);
FORCEPROP 1 LASTPIN (-1525 2050) BN 4
J 0
(-1575 2060);
DISPLAY 0.617021 (-1575 2060);
PAINT PINK (-1575 2060);
FORCEPROP 1 LAST PATH I24
J 0
(-1577 2050);
DISPLAY 0.872340 (-1577 2050);
PAINT GREEN (-1577 2050);
DISPLAY INVISIBLE (-1577 2050);
FORCEPROP 1 LAST HDL_TAP TRUE
J 0
(-1250 1925);
DISPLAY 1.234043 (-1250 1925);
PAINT GREEN (-1250 1925);
DISPLAY INVISIBLE (-1250 1925);
FORCEPROP 1 LAST BODY_TYPE PLUMBING
J 0
(-1575 2000);
DISPLAY 1.234043 (-1575 2000);
PAINT GREEN (-1575 2000);
DISPLAY INVISIBLE (-1575 2000);
FORCEPROP 2 LAST CDS_LIB mstr_standard
J 0
(-1575 2050);
DISPLAY 0.787234 (-1575 2050);
PAINT MONO (-1575 2050);
DISPLAY INVISIBLE (-1575 2050);
FORCEADD TAP..6
(-1575 2150);
FORCEPROP 3 LASTPIN (-1525 2150) SIG_NAME M_B_ECC<6>
J 0
(-1515 2160);
DISPLAY 0.659574 (-1515 2160);
PAINT MONO (-1515 2160);
DISPLAY INVISIBLE (-1515 2160);
FORCEPROP 1 LASTPIN (-1525 2150) BN 6
J 0
(-1575 2160);
DISPLAY 0.617021 (-1575 2160);
PAINT PINK (-1575 2160);
FORCEPROP 1 LAST PATH I25
J 0
(-1577 2150);
DISPLAY 0.872340 (-1577 2150);
PAINT GREEN (-1577 2150);
DISPLAY INVISIBLE (-1577 2150);
FORCEPROP 1 LAST HDL_TAP TRUE
J 0
(-1250 2025);
DISPLAY 1.234043 (-1250 2025);
PAINT GREEN (-1250 2025);
DISPLAY INVISIBLE (-1250 2025);
FORCEPROP 1 LAST BODY_TYPE PLUMBING
J 0
(-1575 2100);
DISPLAY 1.234043 (-1575 2100);
PAINT GREEN (-1575 2100);
DISPLAY INVISIBLE (-1575 2100);
FORCEPROP 2 LAST CDS_LIB mstr_standard
J 0
(-1575 2150);
DISPLAY 0.787234 (-1575 2150);
PAINT MONO (-1575 2150);
DISPLAY INVISIBLE (-1575 2150);
FORCEADD TAP..6
(-1575 2100);
FORCEPROP 3 LASTPIN (-1525 2100) SIG_NAME M_B_ECC<5>
J 0
(-1515 2110);
DISPLAY 0.659574 (-1515 2110);
PAINT MONO (-1515 2110);
DISPLAY INVISIBLE (-1515 2110);
FORCEPROP 1 LASTPIN (-1525 2100) BN 5
J 0
(-1575 2110);
DISPLAY 0.617021 (-1575 2110);
PAINT PINK (-1575 2110);
FORCEPROP 1 LAST PATH I26
J 0
(-1577 2100);
DISPLAY 0.872340 (-1577 2100);
PAINT GREEN (-1577 2100);
DISPLAY INVISIBLE (-1577 2100);
FORCEPROP 1 LAST HDL_TAP TRUE
J 0
(-1250 1975);
DISPLAY 1.234043 (-1250 1975);
PAINT GREEN (-1250 1975);
DISPLAY INVISIBLE (-1250 1975);
FORCEPROP 1 LAST BODY_TYPE PLUMBING
J 0
(-1575 2050);
DISPLAY 1.234043 (-1575 2050);
PAINT GREEN (-1575 2050);
DISPLAY INVISIBLE (-1575 2050);
FORCEPROP 2 LAST CDS_LIB mstr_standard
J 0
(-1575 2100);
DISPLAY 0.787234 (-1575 2100);
PAINT MONO (-1575 2100);
DISPLAY INVISIBLE (-1575 2100);
FORCEADD TAP..6
(-1575 2200);
FORCEPROP 3 LASTPIN (-1525 2200) SIG_NAME M_B_ECC<7>
J 0
(-1515 2210);
DISPLAY 0.659574 (-1515 2210);
PAINT MONO (-1515 2210);
DISPLAY INVISIBLE (-1515 2210);
FORCEPROP 1 LASTPIN (-1525 2200) BN 7
J 0
(-1575 2210);
DISPLAY 0.617021 (-1575 2210);
PAINT PINK (-1575 2210);
FORCEPROP 1 LAST PATH I27
J 0
(-1577 2200);
DISPLAY 0.872340 (-1577 2200);
PAINT GREEN (-1577 2200);
DISPLAY INVISIBLE (-1577 2200);
FORCEPROP 1 LAST HDL_TAP TRUE
J 0
(-1250 2075);
DISPLAY 1.234043 (-1250 2075);
PAINT GREEN (-1250 2075);
DISPLAY INVISIBLE (-1250 2075);
FORCEPROP 1 LAST BODY_TYPE PLUMBING
J 0
(-1575 2150);
DISPLAY 1.234043 (-1575 2150);
PAINT GREEN (-1575 2150);
DISPLAY INVISIBLE (-1575 2150);
FORCEPROP 2 LAST CDS_LIB mstr_standard
J 0
(-1575 2200);
DISPLAY 0.787234 (-1575 2200);
PAINT MONO (-1575 2200);
DISPLAY INVISIBLE (-1575 2200);
FORCEADD TAP..6
(-1575 2350);
FORCEPROP 3 LASTPIN (-1525 2350) SIG_NAME M_B_ODT<3>
J 0
(-1515 2360);
DISPLAY 0.659574 (-1515 2360);
PAINT MONO (-1515 2360);
DISPLAY INVISIBLE (-1515 2360);
FORCEPROP 1 LASTPIN (-1525 2350) BN 3
J 0
(-1575 2360);
DISPLAY 0.617021 (-1575 2360);
PAINT PINK (-1575 2360);
FORCEPROP 1 LAST PATH I28
J 0
(-1577 2350);
DISPLAY 0.872340 (-1577 2350);
PAINT GREEN (-1577 2350);
DISPLAY INVISIBLE (-1577 2350);
FORCEPROP 1 LAST HDL_TAP TRUE
J 0
(-1250 2225);
DISPLAY 1.234043 (-1250 2225);
PAINT GREEN (-1250 2225);
DISPLAY INVISIBLE (-1250 2225);
FORCEPROP 1 LAST BODY_TYPE PLUMBING
J 0
(-1575 2300);
DISPLAY 1.234043 (-1575 2300);
PAINT GREEN (-1575 2300);
DISPLAY INVISIBLE (-1575 2300);
FORCEPROP 2 LAST CDS_LIB mstr_standard
J 0
(-1575 2350);
DISPLAY 0.787234 (-1575 2350);
PAINT MONO (-1575 2350);
DISPLAY INVISIBLE (-1575 2350);
FORCEADD TAP..6
(-1575 2300);
FORCEPROP 3 LASTPIN (-1525 2300) SIG_NAME M_B_ODT<2>
J 0
(-1515 2310);
DISPLAY 0.659574 (-1515 2310);
PAINT MONO (-1515 2310);
DISPLAY INVISIBLE (-1515 2310);
FORCEPROP 1 LASTPIN (-1525 2300) BN 2
J 0
(-1575 2310);
DISPLAY 0.617021 (-1575 2310);
PAINT PINK (-1575 2310);
FORCEPROP 1 LAST PATH I29
J 0
(-1577 2300);
DISPLAY 0.872340 (-1577 2300);
PAINT GREEN (-1577 2300);
DISPLAY INVISIBLE (-1577 2300);
FORCEPROP 1 LAST HDL_TAP TRUE
J 0
(-1250 2175);
DISPLAY 1.234043 (-1250 2175);
PAINT GREEN (-1250 2175);
DISPLAY INVISIBLE (-1250 2175);
FORCEPROP 1 LAST BODY_TYPE PLUMBING
J 0
(-1575 2250);
DISPLAY 1.234043 (-1575 2250);
PAINT GREEN (-1575 2250);
DISPLAY INVISIBLE (-1575 2250);
FORCEPROP 2 LAST CDS_LIB mstr_standard
J 0
(-1575 2300);
DISPLAY 0.787234 (-1575 2300);
PAINT MONO (-1575 2300);
DISPLAY INVISIBLE (-1575 2300);
FORCEADD GND..1
R 2
(-3425 1250);
FORCEPROP 3 LASTPIN (-3425 1300) SIG_NAME GND\g
J 0
(-3415 1310);
DISPLAY 0.659574 (-3415 1310);
PAINT MONO (-3415 1310);
DISPLAY INVISIBLE (-3415 1310);
FORCEPROP 1 LAST HDL_POWER GND
J 2
(-3425 1400);
DISPLAY 0.553191 (-3425 1400);
PAINT GREEN (-3425 1400);
DISPLAY INVISIBLE (-3425 1400);
FORCEPROP 2 LAST ROOM DDR4_CH_A
J 0
(-3425 1255);
PAINT ORANGE (-3425 1255);
DISPLAY INVISIBLE (-3425 1255);
FORCEPROP 1 LAST PATH I3
J 2
(-3500 1250);
DISPLAY 0.872340 (-3500 1250);
PAINT AQUA (-3500 1250);
DISPLAY INVISIBLE (-3500 1250);
FORCEPROP 1 LAST BODY_TYPE PLUMBING
J 2
(-3380 1207);
DISPLAY 0.340426 (-3380 1207);
PAINT GREEN (-3380 1207);
DISPLAY INVISIBLE (-3380 1207);
FORCEPROP 2 LAST BOM_COST MEM
J 0
(-3425 1255);
PAINT ORANGE (-3425 1255);
DISPLAY INVISIBLE (-3425 1255);
FORCEPROP 2 LAST CDS_LIB mstr_symbols
J 0
(-3425 1250);
DISPLAY 0.787234 (-3425 1250);
PAINT MONO (-3425 1250);
DISPLAY INVISIBLE (-3425 1250);
FORCEPROP 1 LAST SIZE 1B
J 2
(-3500 1200);
DISPLAY 1.170213 (-3500 1200);
PAINT GREEN (-3500 1200);
DISPLAY INVISIBLE (-3500 1200);
FORCEPROP 1 LAST VOLTAGE 0
J 0
(-3425 1250);
PAINT SKYBLUE (-3425 1250);
DISPLAY INVISIBLE (-3425 1250);
FORCEADD TAP..6
(-1575 2450);
FORCEPROP 3 LASTPIN (-1525 2450) SIG_NAME M_B_CKE<2>
J 0
(-1515 2460);
DISPLAY 0.659574 (-1515 2460);
PAINT MONO (-1515 2460);
DISPLAY INVISIBLE (-1515 2460);
FORCEPROP 1 LASTPIN (-1525 2450) BN 2
J 0
(-1575 2460);
DISPLAY 0.617021 (-1575 2460);
PAINT PINK (-1575 2460);
FORCEPROP 1 LAST PATH I30
J 0
(-1577 2450);
DISPLAY 0.872340 (-1577 2450);
PAINT GREEN (-1577 2450);
DISPLAY INVISIBLE (-1577 2450);
FORCEPROP 1 LAST HDL_TAP TRUE
J 0
(-1250 2325);
DISPLAY 1.234043 (-1250 2325);
PAINT GREEN (-1250 2325);
DISPLAY INVISIBLE (-1250 2325);
FORCEPROP 1 LAST BODY_TYPE PLUMBING
J 0
(-1575 2400);
DISPLAY 1.234043 (-1575 2400);
PAINT GREEN (-1575 2400);
DISPLAY INVISIBLE (-1575 2400);
FORCEPROP 2 LAST CDS_LIB mstr_standard
J 0
(-1575 2450);
DISPLAY 0.787234 (-1575 2450);
PAINT MONO (-1575 2450);
DISPLAY INVISIBLE (-1575 2450);
FORCEADD TAP..6
(-1575 2650);
FORCEPROP 3 LASTPIN (-1525 2650) SIG_NAME M_B_CS_N<5>
J 0
(-1515 2660);
DISPLAY 0.659574 (-1515 2660);
PAINT MONO (-1515 2660);
DISPLAY INVISIBLE (-1515 2660);
FORCEPROP 1 LASTPIN (-1525 2650) BN 5
J 0
(-1575 2660);
DISPLAY 0.617021 (-1575 2660);
PAINT PINK (-1575 2660);
FORCEPROP 1 LAST PATH I31
J 0
(-1577 2650);
DISPLAY 0.872340 (-1577 2650);
PAINT GREEN (-1577 2650);
DISPLAY INVISIBLE (-1577 2650);
FORCEPROP 1 LAST HDL_TAP TRUE
J 0
(-1250 2525);
DISPLAY 1.234043 (-1250 2525);
PAINT GREEN (-1250 2525);
DISPLAY INVISIBLE (-1250 2525);
FORCEPROP 1 LAST BODY_TYPE PLUMBING
J 0
(-1575 2600);
DISPLAY 1.234043 (-1575 2600);
PAINT GREEN (-1575 2600);
DISPLAY INVISIBLE (-1575 2600);
FORCEPROP 2 LAST CDS_LIB mstr_standard
J 0
(-1575 2650);
DISPLAY 0.787234 (-1575 2650);
PAINT MONO (-1575 2650);
DISPLAY INVISIBLE (-1575 2650);
FORCEADD TAP..6
(-1575 2600);
FORCEPROP 3 LASTPIN (-1525 2600) SIG_NAME M_B_CS_N<4>
J 0
(-1515 2610);
DISPLAY 0.659574 (-1515 2610);
PAINT MONO (-1515 2610);
DISPLAY INVISIBLE (-1515 2610);
FORCEPROP 1 LASTPIN (-1525 2600) BN 4
J 0
(-1575 2610);
DISPLAY 0.617021 (-1575 2610);
PAINT PINK (-1575 2610);
FORCEPROP 1 LAST PATH I32
J 0
(-1577 2600);
DISPLAY 0.872340 (-1577 2600);
PAINT GREEN (-1577 2600);
DISPLAY INVISIBLE (-1577 2600);
FORCEPROP 1 LAST HDL_TAP TRUE
J 0
(-1250 2475);
DISPLAY 1.234043 (-1250 2475);
PAINT GREEN (-1250 2475);
DISPLAY INVISIBLE (-1250 2475);
FORCEPROP 1 LAST BODY_TYPE PLUMBING
J 0
(-1575 2550);
DISPLAY 1.234043 (-1575 2550);
PAINT GREEN (-1575 2550);
DISPLAY INVISIBLE (-1575 2550);
FORCEPROP 2 LAST CDS_LIB mstr_standard
J 0
(-1575 2600);
DISPLAY 0.787234 (-1575 2600);
PAINT MONO (-1575 2600);
DISPLAY INVISIBLE (-1575 2600);
FORCEADD TAP..6
(-1575 2500);
FORCEPROP 3 LASTPIN (-1525 2500) SIG_NAME M_B_CKE<3>
J 0
(-1515 2510);
DISPLAY 0.659574 (-1515 2510);
PAINT MONO (-1515 2510);
DISPLAY INVISIBLE (-1515 2510);
FORCEPROP 1 LASTPIN (-1525 2500) BN 3
J 0
(-1575 2510);
DISPLAY 0.617021 (-1575 2510);
PAINT PINK (-1575 2510);
FORCEPROP 1 LAST PATH I33
J 0
(-1577 2500);
DISPLAY 0.872340 (-1577 2500);
PAINT GREEN (-1577 2500);
DISPLAY INVISIBLE (-1577 2500);
FORCEPROP 1 LAST HDL_TAP TRUE
J 0
(-1250 2375);
DISPLAY 1.234043 (-1250 2375);
PAINT GREEN (-1250 2375);
DISPLAY INVISIBLE (-1250 2375);
FORCEPROP 1 LAST BODY_TYPE PLUMBING
J 0
(-1575 2450);
DISPLAY 1.234043 (-1575 2450);
PAINT GREEN (-1575 2450);
DISPLAY INVISIBLE (-1575 2450);
FORCEPROP 2 LAST CDS_LIB mstr_standard
J 0
(-1575 2500);
DISPLAY 0.787234 (-1575 2500);
PAINT MONO (-1575 2500);
DISPLAY INVISIBLE (-1575 2500);
FORCEADD TAP..6
(-1575 2700);
FORCEPROP 3 LASTPIN (-1525 2700) SIG_NAME M_B_CS_N<6>
J 0
(-1515 2710);
DISPLAY 0.659574 (-1515 2710);
PAINT MONO (-1515 2710);
DISPLAY INVISIBLE (-1515 2710);
FORCEPROP 1 LASTPIN (-1525 2700) BN 6
J 0
(-1575 2710);
DISPLAY 0.617021 (-1575 2710);
PAINT PINK (-1575 2710);
FORCEPROP 1 LAST PATH I34
J 0
(-1577 2700);
DISPLAY 0.872340 (-1577 2700);
PAINT GREEN (-1577 2700);
DISPLAY INVISIBLE (-1577 2700);
FORCEPROP 1 LAST HDL_TAP TRUE
J 0
(-1250 2575);
DISPLAY 1.234043 (-1250 2575);
PAINT GREEN (-1250 2575);
DISPLAY INVISIBLE (-1250 2575);
FORCEPROP 1 LAST BODY_TYPE PLUMBING
J 0
(-1575 2650);
DISPLAY 1.234043 (-1575 2650);
PAINT GREEN (-1575 2650);
DISPLAY INVISIBLE (-1575 2650);
FORCEPROP 2 LAST CDS_LIB mstr_standard
J 0
(-1575 2700);
DISPLAY 0.787234 (-1575 2700);
PAINT MONO (-1575 2700);
DISPLAY INVISIBLE (-1575 2700);
FORCEADD OFFPAGE..1
(-2225 2800);
FORCEPROP 2 LAST $XR1 45 
J 0
(-2566 2800);
DISPLAY 0.638298 (-2566 2800);
PAINT MONO (-2566 2800);
FORCEPROP 2 LAST $XR0 24 
J 0
(-2476 2800);
DISPLAY 0.638298 (-2476 2800);
PAINT MONO (-2476 2800);
FORCEPROP 2 LAST PATH I35
J 0
(-2425 2850);
DISPLAY 1.021277 (-2425 2850);
PAINT ORANGE (-2425 2850);
DISPLAY INVISIBLE (-2425 2850);
FORCEPROP 1 LAST COMMENT_BODY TRUE
J 0
(-2100 2700);
DISPLAY 0.936170 (-2100 2700);
PAINT GREEN (-2100 2700);
DISPLAY INVISIBLE (-2100 2700);
FORCEPROP 1 LAST OFFPAGE TRUE
J 0
(-1900 2675);
DISPLAY 0.936170 (-1900 2675);
PAINT GREEN (-1900 2675);
DISPLAY INVISIBLE (-1900 2675);
FORCEPROP 2 LAST CDS_LIB mstr_standard
J 0
(-2225 2800);
DISPLAY 0.787234 (-2225 2800);
PAINT MONO (-2225 2800);
DISPLAY INVISIBLE (-2225 2800);
FORCEADD OFFPAGE..1
(-2225 2850);
FORCEPROP 2 LAST $XR1 45 
J 0
(-2566 2850);
DISPLAY 0.638298 (-2566 2850);
PAINT MONO (-2566 2850);
FORCEPROP 2 LAST $XR0 24 
J 0
(-2476 2850);
DISPLAY 0.638298 (-2476 2850);
PAINT MONO (-2476 2850);
FORCEPROP 2 LAST PATH I36
J 0
(-2425 2900);
DISPLAY 1.021277 (-2425 2900);
PAINT ORANGE (-2425 2900);
DISPLAY INVISIBLE (-2425 2900);
FORCEPROP 1 LAST COMMENT_BODY TRUE
J 0
(-2100 2750);
DISPLAY 0.936170 (-2100 2750);
PAINT GREEN (-2100 2750);
DISPLAY INVISIBLE (-2100 2750);
FORCEPROP 1 LAST OFFPAGE TRUE
J 0
(-1900 2725);
DISPLAY 0.936170 (-1900 2725);
PAINT GREEN (-1900 2725);
DISPLAY INVISIBLE (-1900 2725);
FORCEPROP 2 LAST CDS_LIB mstr_standard
J 0
(-2225 2850);
DISPLAY 0.787234 (-2225 2850);
PAINT MONO (-2225 2850);
DISPLAY INVISIBLE (-2225 2850);
FORCEADD OFFPAGE..1
(-2225 3250);
FORCEPROP 2 LAST $XR1 45 
J 0
(-2566 3250);
DISPLAY 0.638298 (-2566 3250);
PAINT MONO (-2566 3250);
FORCEPROP 2 LAST $XR0 24 
J 0
(-2476 3250);
DISPLAY 0.638298 (-2476 3250);
PAINT MONO (-2476 3250);
FORCEPROP 2 LAST PATH I37
J 0
(-2425 3300);
DISPLAY 1.021277 (-2425 3300);
PAINT ORANGE (-2425 3300);
DISPLAY INVISIBLE (-2425 3300);
FORCEPROP 1 LAST COMMENT_BODY TRUE
J 0
(-2100 3150);
DISPLAY 0.936170 (-2100 3150);
PAINT GREEN (-2100 3150);
DISPLAY INVISIBLE (-2100 3150);
FORCEPROP 1 LAST OFFPAGE TRUE
J 0
(-1900 3125);
DISPLAY 0.936170 (-1900 3125);
PAINT GREEN (-1900 3125);
DISPLAY INVISIBLE (-1900 3125);
FORCEPROP 2 LAST CDS_LIB mstr_standard
J 0
(-2225 3250);
DISPLAY 0.787234 (-2225 3250);
PAINT MONO (-2225 3250);
DISPLAY INVISIBLE (-2225 3250);
FORCEADD OFFPAGE..1
(-2225 3350);
FORCEPROP 2 LAST $XR1 45 
J 0
(-2566 3350);
DISPLAY 0.638298 (-2566 3350);
PAINT MONO (-2566 3350);
FORCEPROP 2 LAST $XR0 24 
J 0
(-2476 3350);
DISPLAY 0.638298 (-2476 3350);
PAINT MONO (-2476 3350);
FORCEPROP 2 LAST PATH I38
J 0
(-2425 3400);
DISPLAY 1.021277 (-2425 3400);
PAINT ORANGE (-2425 3400);
DISPLAY INVISIBLE (-2425 3400);
FORCEPROP 1 LAST COMMENT_BODY TRUE
J 0
(-2100 3250);
DISPLAY 0.936170 (-2100 3250);
PAINT GREEN (-2100 3250);
DISPLAY INVISIBLE (-2100 3250);
FORCEPROP 1 LAST OFFPAGE TRUE
J 0
(-1900 3225);
DISPLAY 0.936170 (-1900 3225);
PAINT GREEN (-1900 3225);
DISPLAY INVISIBLE (-1900 3225);
FORCEPROP 2 LAST CDS_LIB mstr_standard
J 0
(-2225 3350);
DISPLAY 0.787234 (-2225 3350);
PAINT MONO (-2225 3350);
DISPLAY INVISIBLE (-2225 3350);
FORCEADD TAP..6
(-1775 2900);
FORCEPROP 3 LASTPIN (-1725 2900) SIG_NAME M_B_CLK_DN<2>
J 0
(-1715 2910);
DISPLAY 0.659574 (-1715 2910);
PAINT MONO (-1715 2910);
DISPLAY INVISIBLE (-1715 2910);
FORCEPROP 1 LASTPIN (-1725 2900) BN 2
J 0
(-1775 2910);
DISPLAY 0.617021 (-1775 2910);
PAINT PINK (-1775 2910);
FORCEPROP 1 LAST PATH I39
J 0
(-1777 2900);
DISPLAY 0.872340 (-1777 2900);
PAINT GREEN (-1777 2900);
DISPLAY INVISIBLE (-1777 2900);
FORCEPROP 1 LAST HDL_TAP TRUE
J 0
(-1450 2775);
DISPLAY 1.234043 (-1450 2775);
PAINT GREEN (-1450 2775);
DISPLAY INVISIBLE (-1450 2775);
FORCEPROP 1 LAST BODY_TYPE PLUMBING
J 0
(-1775 2850);
DISPLAY 1.234043 (-1775 2850);
PAINT GREEN (-1775 2850);
DISPLAY INVISIBLE (-1775 2850);
FORCEPROP 2 LAST CDS_LIB mstr_standard
J 0
(-1775 2900);
DISPLAY 0.787234 (-1775 2900);
PAINT MONO (-1775 2900);
DISPLAY INVISIBLE (-1775 2900);
FORCEADD PVPP_ABC..1
(-3425 1600);
FORCEPROP 3 LASTPIN (-3425 1550) SIG_NAME PVPP_ABC\g
J 0
(-3415 1560);
DISPLAY 0.659574 (-3415 1560);
PAINT MONO (-3415 1560);
DISPLAY INVISIBLE (-3415 1560);
FORCEPROP 1 LAST HDL_POWER PVPP_ABC
J 1
(-3425 1650);
DISPLAY 0.872340 (-3425 1650);
PAINT GREEN (-3425 1650);
DISPLAY INVISIBLE (-3425 1650);
FORCEPROP 2 LAST ROOM DDR4_CH_A
J 0
(-3425 1700);
PAINT ORANGE (-3425 1700);
DISPLAY INVISIBLE (-3425 1700);
FORCEPROP 1 LAST PATH I4
J 0
(-3375 1625);
DISPLAY 0.872340 (-3375 1625);
PAINT AQUA (-3375 1625);
DISPLAY INVISIBLE (-3375 1625);
FORCEPROP 1 LAST BODY_TYPE PLUMBING
J 0
(-3470 1557);
DISPLAY 0.340426 (-3470 1557);
PAINT GREEN (-3470 1557);
DISPLAY INVISIBLE (-3470 1557);
FORCEPROP 2 LAST CDS_LIB mstr_symbols
J 0
(-3425 1600);
PAINT ORANGE (-3425 1600);
DISPLAY INVISIBLE (-3425 1600);
FORCEPROP 0 LAST BOM_COST MEM
J 0
(-3425 1700);
PAINT ORANGE (-3425 1700);
DISPLAY INVISIBLE (-3425 1700);
FORCEPROP 1 LAST VOLTAGE 2.5V
J 0
(-3470 1557);
DISPLAY 0.340426 (-3470 1557);
PAINT SKYBLUE (-3470 1557);
DISPLAY INVISIBLE (-3470 1557);
FORCEADD TAP..6
(-1775 3000);
FORCEPROP 3 LASTPIN (-1725 3000) SIG_NAME M_B_CLK_DN<3>
J 0
(-1715 3010);
DISPLAY 0.659574 (-1715 3010);
PAINT MONO (-1715 3010);
DISPLAY INVISIBLE (-1715 3010);
FORCEPROP 1 LASTPIN (-1725 3000) BN 3
J 0
(-1775 3010);
DISPLAY 0.617021 (-1775 3010);
PAINT PINK (-1775 3010);
FORCEPROP 1 LAST PATH I40
J 0
(-1777 3000);
DISPLAY 0.872340 (-1777 3000);
PAINT GREEN (-1777 3000);
DISPLAY INVISIBLE (-1777 3000);
FORCEPROP 1 LAST HDL_TAP TRUE
J 0
(-1450 2875);
DISPLAY 1.234043 (-1450 2875);
PAINT GREEN (-1450 2875);
DISPLAY INVISIBLE (-1450 2875);
FORCEPROP 1 LAST BODY_TYPE PLUMBING
J 0
(-1775 2950);
DISPLAY 1.234043 (-1775 2950);
PAINT GREEN (-1775 2950);
DISPLAY INVISIBLE (-1775 2950);
FORCEPROP 2 LAST CDS_LIB mstr_standard
J 0
(-1775 3000);
DISPLAY 0.787234 (-1775 3000);
PAINT MONO (-1775 3000);
DISPLAY INVISIBLE (-1775 3000);
FORCEADD TAP..6
(-1575 2750);
FORCEPROP 3 LASTPIN (-1525 2750) SIG_NAME M_B_CS_N<7>
J 0
(-1515 2760);
DISPLAY 0.659574 (-1515 2760);
PAINT MONO (-1515 2760);
DISPLAY INVISIBLE (-1515 2760);
FORCEPROP 1 LASTPIN (-1525 2750) BN 7
J 0
(-1575 2760);
DISPLAY 0.617021 (-1575 2760);
PAINT PINK (-1575 2760);
FORCEPROP 1 LAST PATH I41
J 0
(-1577 2750);
DISPLAY 0.872340 (-1577 2750);
PAINT GREEN (-1577 2750);
DISPLAY INVISIBLE (-1577 2750);
FORCEPROP 1 LAST HDL_TAP TRUE
J 0
(-1250 2625);
DISPLAY 1.234043 (-1250 2625);
PAINT GREEN (-1250 2625);
DISPLAY INVISIBLE (-1250 2625);
FORCEPROP 1 LAST BODY_TYPE PLUMBING
J 0
(-1575 2700);
DISPLAY 1.234043 (-1575 2700);
PAINT GREEN (-1575 2700);
DISPLAY INVISIBLE (-1575 2700);
FORCEPROP 2 LAST CDS_LIB mstr_standard
J 0
(-1575 2750);
DISPLAY 0.787234 (-1575 2750);
PAINT MONO (-1575 2750);
DISPLAY INVISIBLE (-1575 2750);
FORCEADD TAP..6
(-1575 2950);
FORCEPROP 3 LASTPIN (-1525 2950) SIG_NAME M_B_CLK_DP<2>
J 0
(-1515 2960);
DISPLAY 0.659574 (-1515 2960);
PAINT MONO (-1515 2960);
DISPLAY INVISIBLE (-1515 2960);
FORCEPROP 1 LASTPIN (-1525 2950) BN 2
J 0
(-1575 2960);
DISPLAY 0.617021 (-1575 2960);
PAINT PINK (-1575 2960);
FORCEPROP 1 LAST PATH I42
J 0
(-1577 2950);
DISPLAY 0.872340 (-1577 2950);
PAINT GREEN (-1577 2950);
DISPLAY INVISIBLE (-1577 2950);
FORCEPROP 1 LAST HDL_TAP TRUE
J 0
(-1250 2825);
DISPLAY 1.234043 (-1250 2825);
PAINT GREEN (-1250 2825);
DISPLAY INVISIBLE (-1250 2825);
FORCEPROP 1 LAST BODY_TYPE PLUMBING
J 0
(-1575 2900);
DISPLAY 1.234043 (-1575 2900);
PAINT GREEN (-1575 2900);
DISPLAY INVISIBLE (-1575 2900);
FORCEPROP 2 LAST CDS_LIB mstr_standard
J 0
(-1575 2950);
DISPLAY 0.787234 (-1575 2950);
PAINT MONO (-1575 2950);
DISPLAY INVISIBLE (-1575 2950);
FORCEADD TAP..6
(-1575 3150);
FORCEPROP 3 LASTPIN (-1525 3150) SIG_NAME M_B_BG<0>
J 0
(-1515 3160);
DISPLAY 0.659574 (-1515 3160);
PAINT MONO (-1515 3160);
DISPLAY INVISIBLE (-1515 3160);
FORCEPROP 1 LASTPIN (-1525 3150) BN 0
J 0
(-1575 3160);
DISPLAY 0.617021 (-1575 3160);
PAINT PINK (-1575 3160);
FORCEPROP 1 LAST PATH I43
J 0
(-1577 3150);
DISPLAY 0.872340 (-1577 3150);
PAINT GREEN (-1577 3150);
DISPLAY INVISIBLE (-1577 3150);
FORCEPROP 1 LAST HDL_TAP TRUE
J 0
(-1250 3025);
DISPLAY 1.234043 (-1250 3025);
PAINT GREEN (-1250 3025);
DISPLAY INVISIBLE (-1250 3025);
FORCEPROP 1 LAST BODY_TYPE PLUMBING
J 0
(-1575 3100);
DISPLAY 1.234043 (-1575 3100);
PAINT GREEN (-1575 3100);
DISPLAY INVISIBLE (-1575 3100);
FORCEPROP 2 LAST CDS_LIB mstr_standard
J 0
(-1575 3150);
DISPLAY 0.787234 (-1575 3150);
PAINT MONO (-1575 3150);
DISPLAY INVISIBLE (-1575 3150);
FORCEADD TAP..6
(-1575 3200);
FORCEPROP 3 LASTPIN (-1525 3200) SIG_NAME M_B_BG<1>
J 0
(-1515 3210);
DISPLAY 0.659574 (-1515 3210);
PAINT MONO (-1515 3210);
DISPLAY INVISIBLE (-1515 3210);
FORCEPROP 1 LASTPIN (-1525 3200) BN 1
J 0
(-1575 3210);
DISPLAY 0.617021 (-1575 3210);
PAINT PINK (-1575 3210);
FORCEPROP 1 LAST PATH I44
J 0
(-1577 3200);
DISPLAY 0.872340 (-1577 3200);
PAINT GREEN (-1577 3200);
DISPLAY INVISIBLE (-1577 3200);
FORCEPROP 1 LAST HDL_TAP TRUE
J 0
(-1250 3075);
DISPLAY 1.234043 (-1250 3075);
PAINT GREEN (-1250 3075);
DISPLAY INVISIBLE (-1250 3075);
FORCEPROP 1 LAST BODY_TYPE PLUMBING
J 0
(-1575 3150);
DISPLAY 1.234043 (-1575 3150);
PAINT GREEN (-1575 3150);
DISPLAY INVISIBLE (-1575 3150);
FORCEPROP 2 LAST CDS_LIB mstr_standard
J 0
(-1575 3200);
DISPLAY 0.787234 (-1575 3200);
PAINT MONO (-1575 3200);
DISPLAY INVISIBLE (-1575 3200);
FORCEADD TAP..6
(-1575 3050);
FORCEPROP 3 LASTPIN (-1525 3050) SIG_NAME M_B_CLK_DP<3>
J 0
(-1515 3060);
DISPLAY 0.659574 (-1515 3060);
PAINT MONO (-1515 3060);
DISPLAY INVISIBLE (-1515 3060);
FORCEPROP 1 LASTPIN (-1525 3050) BN 3
J 0
(-1575 3060);
DISPLAY 0.617021 (-1575 3060);
PAINT PINK (-1575 3060);
FORCEPROP 1 LAST PATH I45
J 0
(-1577 3050);
DISPLAY 0.872340 (-1577 3050);
PAINT GREEN (-1577 3050);
DISPLAY INVISIBLE (-1577 3050);
FORCEPROP 1 LAST HDL_TAP TRUE
J 0
(-1250 2925);
DISPLAY 1.234043 (-1250 2925);
PAINT GREEN (-1250 2925);
DISPLAY INVISIBLE (-1250 2925);
FORCEPROP 1 LAST BODY_TYPE PLUMBING
J 0
(-1575 3000);
DISPLAY 1.234043 (-1575 3000);
PAINT GREEN (-1575 3000);
DISPLAY INVISIBLE (-1575 3000);
FORCEPROP 2 LAST CDS_LIB mstr_standard
J 0
(-1575 3050);
DISPLAY 0.787234 (-1575 3050);
PAINT MONO (-1575 3050);
DISPLAY INVISIBLE (-1575 3050);
FORCEADD TAP..6
(-1575 3450);
FORCEPROP 3 LASTPIN (-1525 3450) SIG_NAME M_B_MA<1>
J 0
(-1515 3460);
DISPLAY 0.659574 (-1515 3460);
PAINT MONO (-1515 3460);
DISPLAY INVISIBLE (-1515 3460);
FORCEPROP 1 LASTPIN (-1525 3450) BN 1
J 0
(-1575 3460);
DISPLAY 0.617021 (-1575 3460);
PAINT PINK (-1575 3460);
FORCEPROP 1 LAST PATH I46
J 0
(-1577 3450);
DISPLAY 0.872340 (-1577 3450);
PAINT GREEN (-1577 3450);
DISPLAY INVISIBLE (-1577 3450);
FORCEPROP 1 LAST HDL_TAP TRUE
J 0
(-1250 3325);
DISPLAY 1.234043 (-1250 3325);
PAINT GREEN (-1250 3325);
DISPLAY INVISIBLE (-1250 3325);
FORCEPROP 1 LAST BODY_TYPE PLUMBING
J 0
(-1575 3400);
DISPLAY 1.234043 (-1575 3400);
PAINT GREEN (-1575 3400);
DISPLAY INVISIBLE (-1575 3400);
FORCEPROP 2 LAST CDS_LIB mstr_standard
J 2
(-1575 3450);
DISPLAY 0.787234 (-1575 3450);
PAINT MONO (-1575 3450);
DISPLAY INVISIBLE (-1575 3450);
FORCEADD TAP..6
(-1575 3400);
FORCEPROP 3 LASTPIN (-1525 3400) SIG_NAME M_B_MA<0>
J 0
(-1515 3410);
DISPLAY 0.659574 (-1515 3410);
PAINT MONO (-1515 3410);
DISPLAY INVISIBLE (-1515 3410);
FORCEPROP 1 LASTPIN (-1525 3400) BN 0
J 0
(-1575 3410);
DISPLAY 0.617021 (-1575 3410);
PAINT PINK (-1575 3410);
FORCEPROP 1 LAST PATH I47
J 0
(-1577 3400);
DISPLAY 0.872340 (-1577 3400);
PAINT GREEN (-1577 3400);
DISPLAY INVISIBLE (-1577 3400);
FORCEPROP 1 LAST HDL_TAP TRUE
J 0
(-1250 3275);
DISPLAY 1.234043 (-1250 3275);
PAINT GREEN (-1250 3275);
DISPLAY INVISIBLE (-1250 3275);
FORCEPROP 1 LAST BODY_TYPE PLUMBING
J 0
(-1575 3350);
DISPLAY 1.234043 (-1575 3350);
PAINT GREEN (-1575 3350);
DISPLAY INVISIBLE (-1575 3350);
FORCEPROP 2 LAST CDS_LIB mstr_standard
J 2
(-1575 3400);
DISPLAY 0.787234 (-1575 3400);
PAINT MONO (-1575 3400);
DISPLAY INVISIBLE (-1575 3400);
FORCEADD TAP..6
(-1575 3250);
FORCEPROP 3 LASTPIN (-1525 3250) SIG_NAME M_B_BA<0>
J 0
(-1515 3260);
DISPLAY 0.659574 (-1515 3260);
PAINT MONO (-1515 3260);
DISPLAY INVISIBLE (-1515 3260);
FORCEPROP 1 LASTPIN (-1525 3250) BN 0
J 0
(-1575 3260);
DISPLAY 0.617021 (-1575 3260);
PAINT PINK (-1575 3260);
FORCEPROP 1 LAST PATH I48
J 0
(-1577 3250);
DISPLAY 0.872340 (-1577 3250);
PAINT GREEN (-1577 3250);
DISPLAY INVISIBLE (-1577 3250);
FORCEPROP 1 LAST HDL_TAP TRUE
J 0
(-1250 3125);
DISPLAY 1.234043 (-1250 3125);
PAINT GREEN (-1250 3125);
DISPLAY INVISIBLE (-1250 3125);
FORCEPROP 1 LAST BODY_TYPE PLUMBING
J 0
(-1575 3200);
DISPLAY 1.234043 (-1575 3200);
PAINT GREEN (-1575 3200);
DISPLAY INVISIBLE (-1575 3200);
FORCEPROP 2 LAST CDS_LIB mstr_standard
J 0
(-1575 3250);
DISPLAY 0.787234 (-1575 3250);
PAINT MONO (-1575 3250);
DISPLAY INVISIBLE (-1575 3250);
FORCEADD TAP..6
(-1575 3300);
FORCEPROP 3 LASTPIN (-1525 3300) SIG_NAME M_B_BA<1>
J 0
(-1515 3310);
DISPLAY 0.659574 (-1515 3310);
PAINT MONO (-1515 3310);
DISPLAY INVISIBLE (-1515 3310);
FORCEPROP 1 LASTPIN (-1525 3300) BN 1
J 0
(-1575 3310);
DISPLAY 0.617021 (-1575 3310);
PAINT PINK (-1575 3310);
FORCEPROP 1 LAST PATH I49
J 0
(-1577 3300);
DISPLAY 0.872340 (-1577 3300);
PAINT GREEN (-1577 3300);
DISPLAY INVISIBLE (-1577 3300);
FORCEPROP 1 LAST HDL_TAP TRUE
J 0
(-1250 3175);
DISPLAY 1.234043 (-1250 3175);
PAINT GREEN (-1250 3175);
DISPLAY INVISIBLE (-1250 3175);
FORCEPROP 1 LAST BODY_TYPE PLUMBING
J 0
(-1575 3250);
DISPLAY 1.234043 (-1575 3250);
PAINT GREEN (-1575 3250);
DISPLAY INVISIBLE (-1575 3250);
FORCEPROP 2 LAST CDS_LIB mstr_standard
J 0
(-1575 3300);
DISPLAY 0.787234 (-1575 3300);
PAINT MONO (-1575 3300);
DISPLAY INVISIBLE (-1575 3300);
FORCEADD CAP_A..1
R 2
(-2975 900);
FORCEPROP 1 LASTPIN (-2975 800) $PN 2
J 2
(-2985 780);
DISPLAY 0.617021 (-2985 780);
PAINT ORANGE (-2985 780);
FORCEPROP 1 LASTPIN (-2975 1000) $PN 1
J 2
(-2985 980);
DISPLAY 0.617021 (-2985 980);
PAINT ORANGE (-2985 980);
FORCEPROP 1 LAST MATERIAL X7R
J 2
(-3025 800);
DISPLAY 0.617021 (-3025 800);
PAINT SKYBLUE (-3025 800);
FORCEPROP 1 LAST VOLTAGE 25V
J 2
(-3025 900);
DISPLAY 0.617021 (-3025 900);
PAINT SKYBLUE (-3025 900);
FORCEPROP 1 LAST PACK_TYPE 0402V
J 2
(-3025 700);
DISPLAY 0.617021 (-3025 700);
PAINT SKYBLUE (-3025 700);
FORCEPROP 1 LAST TOLERANCE 10%
J 2
(-3025 850);
DISPLAY 0.617021 (-3025 850);
PAINT SKYBLUE (-3025 850);
FORCEPROP 1 LAST VALUE 0.01UF
J 2
(-3025 950);
DISPLAY 0.617021 (-3025 950);
PAINT SKYBLUE (-3025 950);
FORCEPROP 1 LAST PART_NUMBER A36096-045
J 2
(-3025 750);
DISPLAY 0.617021 (-3025 750);
PAINT BLUE (-3025 750);
FORCEPROP 1 LAST LOCATION C6U9
J 2
(-3025 1000);
DISPLAY 0.617021 (-3025 1000);
PAINT AQUA (-3025 1000);
FORCEPROP 2 LAST ROOM DDR4_CH_A
J 0
(-2975 900);
PAINT ORANGE (-2975 900);
DISPLAY INVISIBLE (-2975 900);
FORCEPROP 1 LAST PATH I5
J 2
(-3025 1050);
DISPLAY 0.978723 (-3025 1050);
PAINT WHITE (-3025 1050);
DISPLAY INVISIBLE (-3025 1050);
FORCEPROP 2 LAST SEC 1
J 0
(-3025 1100);
PAINT MONO (-3025 1100);
DISPLAY INVISIBLE (-3025 1100);
FORCEPROP 2 LAST SEC_TYPE 0402V
J 0
(-3025 1100);
DISPLAY 1.021277 (-3025 1100);
PAINT ORANGE (-3025 1100);
DISPLAY INVISIBLE (-3025 1100);
FORCEPROP 2 LAST CDS_SEC 1
J 0
(-3025 1050);
PAINT ORANGE (-3025 1050);
DISPLAY INVISIBLE (-3025 1050);
FORCEPROP 2 LAST CDS_LIB dev_discrete
J 0
(-2975 900);
PAINT ORANGE (-2975 900);
DISPLAY INVISIBLE (-2975 900);
FORCEPROP 2 LAST BOM_COST MEM
J 0
(-2975 900);
PAINT ORANGE (-2975 900);
DISPLAY INVISIBLE (-2975 900);
FORCEPROP 2 LAST CDS_LOCATION C6U9
J 2
(-3025 1000);
DISPLAY 0.617021 (-3025 1000);
PAINT AQUA (-3025 1000);
DISPLAY INVISIBLE (-3025 1000);
FORCEADD TAP..6
(-1575 3500);
FORCEPROP 3 LASTPIN (-1525 3500) SIG_NAME M_B_MA<2>
J 0
(-1515 3510);
DISPLAY 0.659574 (-1515 3510);
PAINT MONO (-1515 3510);
DISPLAY INVISIBLE (-1515 3510);
FORCEPROP 1 LASTPIN (-1525 3500) BN 2
J 0
(-1575 3510);
DISPLAY 0.617021 (-1575 3510);
PAINT PINK (-1575 3510);
FORCEPROP 1 LAST PATH I50
J 0
(-1577 3500);
DISPLAY 0.872340 (-1577 3500);
PAINT GREEN (-1577 3500);
DISPLAY INVISIBLE (-1577 3500);
FORCEPROP 1 LAST HDL_TAP TRUE
J 0
(-1250 3375);
DISPLAY 1.234043 (-1250 3375);
PAINT GREEN (-1250 3375);
DISPLAY INVISIBLE (-1250 3375);
FORCEPROP 1 LAST BODY_TYPE PLUMBING
J 0
(-1575 3450);
DISPLAY 1.234043 (-1575 3450);
PAINT GREEN (-1575 3450);
DISPLAY INVISIBLE (-1575 3450);
FORCEPROP 2 LAST CDS_LIB mstr_standard
J 2
(-1575 3500);
DISPLAY 0.787234 (-1575 3500);
PAINT MONO (-1575 3500);
DISPLAY INVISIBLE (-1575 3500);
FORCEADD TAP..6
(-1575 3550);
FORCEPROP 3 LASTPIN (-1525 3550) SIG_NAME M_B_MA<3>
J 0
(-1515 3560);
DISPLAY 0.659574 (-1515 3560);
PAINT MONO (-1515 3560);
DISPLAY INVISIBLE (-1515 3560);
FORCEPROP 1 LASTPIN (-1525 3550) BN 3
J 0
(-1575 3560);
DISPLAY 0.617021 (-1575 3560);
PAINT PINK (-1575 3560);
FORCEPROP 1 LAST PATH I51
J 0
(-1577 3550);
DISPLAY 0.872340 (-1577 3550);
PAINT GREEN (-1577 3550);
DISPLAY INVISIBLE (-1577 3550);
FORCEPROP 1 LAST HDL_TAP TRUE
J 0
(-1250 3425);
DISPLAY 1.234043 (-1250 3425);
PAINT GREEN (-1250 3425);
DISPLAY INVISIBLE (-1250 3425);
FORCEPROP 1 LAST BODY_TYPE PLUMBING
J 0
(-1575 3500);
DISPLAY 1.234043 (-1575 3500);
PAINT GREEN (-1575 3500);
DISPLAY INVISIBLE (-1575 3500);
FORCEPROP 2 LAST CDS_LIB mstr_standard
J 2
(-1575 3550);
DISPLAY 0.787234 (-1575 3550);
PAINT MONO (-1575 3550);
DISPLAY INVISIBLE (-1575 3550);
FORCEADD TAP..6
(-1575 3700);
FORCEPROP 3 LASTPIN (-1525 3700) SIG_NAME M_B_MA<6>
J 0
(-1515 3710);
DISPLAY 0.659574 (-1515 3710);
PAINT MONO (-1515 3710);
DISPLAY INVISIBLE (-1515 3710);
FORCEPROP 1 LASTPIN (-1525 3700) BN 6
J 0
(-1575 3710);
DISPLAY 0.617021 (-1575 3710);
PAINT PINK (-1575 3710);
FORCEPROP 1 LAST PATH I52
J 0
(-1577 3700);
DISPLAY 0.872340 (-1577 3700);
PAINT GREEN (-1577 3700);
DISPLAY INVISIBLE (-1577 3700);
FORCEPROP 1 LAST HDL_TAP TRUE
J 0
(-1250 3575);
DISPLAY 1.234043 (-1250 3575);
PAINT GREEN (-1250 3575);
DISPLAY INVISIBLE (-1250 3575);
FORCEPROP 1 LAST BODY_TYPE PLUMBING
J 0
(-1575 3650);
DISPLAY 1.234043 (-1575 3650);
PAINT GREEN (-1575 3650);
DISPLAY INVISIBLE (-1575 3650);
FORCEPROP 2 LAST CDS_LIB mstr_standard
J 2
(-1575 3700);
DISPLAY 0.787234 (-1575 3700);
PAINT MONO (-1575 3700);
DISPLAY INVISIBLE (-1575 3700);
FORCEADD TAP..6
(-1575 3650);
FORCEPROP 3 LASTPIN (-1525 3650) SIG_NAME M_B_MA<5>
J 0
(-1515 3660);
DISPLAY 0.659574 (-1515 3660);
PAINT MONO (-1515 3660);
DISPLAY INVISIBLE (-1515 3660);
FORCEPROP 1 LASTPIN (-1525 3650) BN 5
J 0
(-1575 3660);
DISPLAY 0.617021 (-1575 3660);
PAINT PINK (-1575 3660);
FORCEPROP 1 LAST PATH I53
J 0
(-1577 3650);
DISPLAY 0.872340 (-1577 3650);
PAINT GREEN (-1577 3650);
DISPLAY INVISIBLE (-1577 3650);
FORCEPROP 1 LAST HDL_TAP TRUE
J 0
(-1250 3525);
DISPLAY 1.234043 (-1250 3525);
PAINT GREEN (-1250 3525);
DISPLAY INVISIBLE (-1250 3525);
FORCEPROP 1 LAST BODY_TYPE PLUMBING
J 0
(-1575 3600);
DISPLAY 1.234043 (-1575 3600);
PAINT GREEN (-1575 3600);
DISPLAY INVISIBLE (-1575 3600);
FORCEPROP 2 LAST CDS_LIB mstr_standard
J 2
(-1575 3650);
DISPLAY 0.787234 (-1575 3650);
PAINT MONO (-1575 3650);
DISPLAY INVISIBLE (-1575 3650);
FORCEADD TAP..6
(-1575 3600);
FORCEPROP 3 LASTPIN (-1525 3600) SIG_NAME M_B_MA<4>
J 0
(-1515 3610);
DISPLAY 0.659574 (-1515 3610);
PAINT MONO (-1515 3610);
DISPLAY INVISIBLE (-1515 3610);
FORCEPROP 1 LASTPIN (-1525 3600) BN 4
J 0
(-1575 3610);
DISPLAY 0.617021 (-1575 3610);
PAINT PINK (-1575 3610);
FORCEPROP 1 LAST PATH I54
J 0
(-1577 3600);
DISPLAY 0.872340 (-1577 3600);
PAINT GREEN (-1577 3600);
DISPLAY INVISIBLE (-1577 3600);
FORCEPROP 1 LAST HDL_TAP TRUE
J 0
(-1250 3475);
DISPLAY 1.234043 (-1250 3475);
PAINT GREEN (-1250 3475);
DISPLAY INVISIBLE (-1250 3475);
FORCEPROP 1 LAST BODY_TYPE PLUMBING
J 0
(-1575 3550);
DISPLAY 1.234043 (-1575 3550);
PAINT GREEN (-1575 3550);
DISPLAY INVISIBLE (-1575 3550);
FORCEPROP 2 LAST CDS_LIB mstr_standard
J 2
(-1575 3600);
DISPLAY 0.787234 (-1575 3600);
PAINT MONO (-1575 3600);
DISPLAY INVISIBLE (-1575 3600);
FORCEADD TAP..6
R 2
(-75 1150);
FORCEPROP 3 LASTPIN (-125 1150) SIG_NAME M_B_DQ<1>
J 0
(-115 1160);
DISPLAY 0.659574 (-115 1160);
PAINT MONO (-115 1160);
DISPLAY INVISIBLE (-115 1160);
FORCEPROP 1 LASTPIN (-125 1150) BN 1
J 2
(-75 1160);
DISPLAY 0.617021 (-75 1160);
PAINT PINK (-75 1160);
FORCEPROP 1 LAST PATH I55
J 2
(-73 1150);
DISPLAY 0.872340 (-73 1150);
PAINT GREEN (-73 1150);
DISPLAY INVISIBLE (-73 1150);
FORCEPROP 1 LAST HDL_TAP TRUE
J 2
(-400 1025);
DISPLAY 1.234043 (-400 1025);
PAINT GREEN (-400 1025);
DISPLAY INVISIBLE (-400 1025);
FORCEPROP 1 LAST BODY_TYPE PLUMBING
J 2
(-75 1100);
DISPLAY 1.234043 (-75 1100);
PAINT GREEN (-75 1100);
DISPLAY INVISIBLE (-75 1100);
FORCEPROP 2 LAST CDS_LIB mstr_standard
J 2
(-75 1150);
DISPLAY 0.787234 (-75 1150);
PAINT MONO (-75 1150);
DISPLAY INVISIBLE (-75 1150);
FORCEADD TAP..6
R 2
(-75 1100);
FORCEPROP 3 LASTPIN (-125 1100) SIG_NAME M_B_DQ<0>
J 0
(-115 1110);
DISPLAY 0.659574 (-115 1110);
PAINT MONO (-115 1110);
DISPLAY INVISIBLE (-115 1110);
FORCEPROP 1 LASTPIN (-125 1100) BN 0
J 2
(-75 1110);
DISPLAY 0.617021 (-75 1110);
PAINT PINK (-75 1110);
FORCEPROP 1 LAST PATH I56
J 2
(-73 1100);
DISPLAY 0.872340 (-73 1100);
PAINT GREEN (-73 1100);
DISPLAY INVISIBLE (-73 1100);
FORCEPROP 1 LAST HDL_TAP TRUE
J 2
(-400 975);
DISPLAY 1.234043 (-400 975);
PAINT GREEN (-400 975);
DISPLAY INVISIBLE (-400 975);
FORCEPROP 1 LAST BODY_TYPE PLUMBING
J 2
(-75 1050);
DISPLAY 1.234043 (-75 1050);
PAINT GREEN (-75 1050);
DISPLAY INVISIBLE (-75 1050);
FORCEPROP 2 LAST CDS_LIB mstr_standard
J 2
(-75 1100);
DISPLAY 0.787234 (-75 1100);
PAINT MONO (-75 1100);
DISPLAY INVISIBLE (-75 1100);
FORCEADD TAP..6
R 2
(-75 1250);
FORCEPROP 3 LASTPIN (-125 1250) SIG_NAME M_B_DQ<3>
J 0
(-115 1260);
DISPLAY 0.659574 (-115 1260);
PAINT MONO (-115 1260);
DISPLAY INVISIBLE (-115 1260);
FORCEPROP 1 LASTPIN (-125 1250) BN 3
J 2
(-75 1260);
DISPLAY 0.617021 (-75 1260);
PAINT PINK (-75 1260);
FORCEPROP 1 LAST PATH I57
J 2
(-73 1250);
DISPLAY 0.872340 (-73 1250);
PAINT GREEN (-73 1250);
DISPLAY INVISIBLE (-73 1250);
FORCEPROP 1 LAST HDL_TAP TRUE
J 2
(-400 1125);
DISPLAY 1.234043 (-400 1125);
PAINT GREEN (-400 1125);
DISPLAY INVISIBLE (-400 1125);
FORCEPROP 1 LAST BODY_TYPE PLUMBING
J 2
(-75 1200);
DISPLAY 1.234043 (-75 1200);
PAINT GREEN (-75 1200);
DISPLAY INVISIBLE (-75 1200);
FORCEPROP 2 LAST CDS_LIB mstr_standard
J 2
(-75 1250);
DISPLAY 0.787234 (-75 1250);
PAINT MONO (-75 1250);
DISPLAY INVISIBLE (-75 1250);
FORCEADD TAP..6
R 2
(-75 1200);
FORCEPROP 3 LASTPIN (-125 1200) SIG_NAME M_B_DQ<2>
J 0
(-115 1210);
DISPLAY 0.659574 (-115 1210);
PAINT MONO (-115 1210);
DISPLAY INVISIBLE (-115 1210);
FORCEPROP 1 LASTPIN (-125 1200) BN 2
J 2
(-75 1210);
DISPLAY 0.617021 (-75 1210);
PAINT PINK (-75 1210);
FORCEPROP 1 LAST PATH I58
J 2
(-73 1200);
DISPLAY 0.872340 (-73 1200);
PAINT GREEN (-73 1200);
DISPLAY INVISIBLE (-73 1200);
FORCEPROP 1 LAST HDL_TAP TRUE
J 2
(-400 1075);
DISPLAY 1.234043 (-400 1075);
PAINT GREEN (-400 1075);
DISPLAY INVISIBLE (-400 1075);
FORCEPROP 1 LAST BODY_TYPE PLUMBING
J 2
(-75 1150);
DISPLAY 1.234043 (-75 1150);
PAINT GREEN (-75 1150);
DISPLAY INVISIBLE (-75 1150);
FORCEPROP 2 LAST CDS_LIB mstr_standard
J 2
(-75 1200);
DISPLAY 0.787234 (-75 1200);
PAINT MONO (-75 1200);
DISPLAY INVISIBLE (-75 1200);
FORCEADD TAP..6
R 2
(-75 1300);
FORCEPROP 3 LASTPIN (-125 1300) SIG_NAME M_B_DQ<4>
J 0
(-115 1310);
DISPLAY 0.659574 (-115 1310);
PAINT MONO (-115 1310);
DISPLAY INVISIBLE (-115 1310);
FORCEPROP 1 LASTPIN (-125 1300) BN 4
J 2
(-75 1310);
DISPLAY 0.617021 (-75 1310);
PAINT PINK (-75 1310);
FORCEPROP 1 LAST PATH I59
J 2
(-73 1300);
DISPLAY 0.872340 (-73 1300);
PAINT GREEN (-73 1300);
DISPLAY INVISIBLE (-73 1300);
FORCEPROP 1 LAST HDL_TAP TRUE
J 2
(-400 1175);
DISPLAY 1.234043 (-400 1175);
PAINT GREEN (-400 1175);
DISPLAY INVISIBLE (-400 1175);
FORCEPROP 1 LAST BODY_TYPE PLUMBING
J 2
(-75 1250);
DISPLAY 1.234043 (-75 1250);
PAINT GREEN (-75 1250);
DISPLAY INVISIBLE (-75 1250);
FORCEPROP 2 LAST CDS_LIB mstr_standard
J 2
(-75 1300);
DISPLAY 0.787234 (-75 1300);
PAINT MONO (-75 1300);
DISPLAY INVISIBLE (-75 1300);
FORCEADD OFFPAGE..5
(-2400 1600);
FORCEPROP 2 LAST $XR1 24 
J 0
(-2714 1600);
DISPLAY 0.638298 (-2714 1600);
PAINT MONO (-2714 1600);
FORCEPROP 2 LAST $XR0 45 
J 0
(-2624 1600);
DISPLAY 0.638298 (-2624 1600);
PAINT MONO (-2624 1600);
FORCEPROP 2 LAST PATH I6
J 0
(-2575 1650);
DISPLAY 1.021277 (-2575 1650);
PAINT ORANGE (-2575 1650);
DISPLAY INVISIBLE (-2575 1650);
FORCEPROP 1 LAST COMMENT_BODY TRUE
J 0
(-2300 1525);
DISPLAY 1.404255 (-2300 1525);
PAINT GREEN (-2300 1525);
DISPLAY INVISIBLE (-2300 1525);
FORCEPROP 1 LAST OFFPAGE TRUE
J 0
(-2075 1475);
DISPLAY 1.404255 (-2075 1475);
PAINT GREEN (-2075 1475);
DISPLAY INVISIBLE (-2075 1475);
FORCEPROP 2 LAST CDS_LIB mstr_standard
J 0
(-2400 1600);
DISPLAY 0.787234 (-2400 1600);
PAINT MONO (-2400 1600);
DISPLAY INVISIBLE (-2400 1600);
FORCEADD TAP..6
R 2
(-75 1400);
FORCEPROP 3 LASTPIN (-125 1400) SIG_NAME M_B_DQ<6>
J 0
(-115 1410);
DISPLAY 0.659574 (-115 1410);
PAINT MONO (-115 1410);
DISPLAY INVISIBLE (-115 1410);
FORCEPROP 1 LASTPIN (-125 1400) BN 6
J 2
(-75 1410);
DISPLAY 0.617021 (-75 1410);
PAINT PINK (-75 1410);
FORCEPROP 1 LAST PATH I60
J 2
(-73 1400);
DISPLAY 0.872340 (-73 1400);
PAINT GREEN (-73 1400);
DISPLAY INVISIBLE (-73 1400);
FORCEPROP 1 LAST HDL_TAP TRUE
J 2
(-400 1275);
DISPLAY 1.234043 (-400 1275);
PAINT GREEN (-400 1275);
DISPLAY INVISIBLE (-400 1275);
FORCEPROP 1 LAST BODY_TYPE PLUMBING
J 2
(-75 1350);
DISPLAY 1.234043 (-75 1350);
PAINT GREEN (-75 1350);
DISPLAY INVISIBLE (-75 1350);
FORCEPROP 2 LAST CDS_LIB mstr_standard
J 2
(-75 1400);
DISPLAY 0.787234 (-75 1400);
PAINT MONO (-75 1400);
DISPLAY INVISIBLE (-75 1400);
FORCEADD TAP..6
R 2
(-75 1350);
FORCEPROP 3 LASTPIN (-125 1350) SIG_NAME M_B_DQ<5>
J 0
(-115 1360);
DISPLAY 0.659574 (-115 1360);
PAINT MONO (-115 1360);
DISPLAY INVISIBLE (-115 1360);
FORCEPROP 1 LASTPIN (-125 1350) BN 5
J 2
(-75 1360);
DISPLAY 0.617021 (-75 1360);
PAINT PINK (-75 1360);
FORCEPROP 1 LAST PATH I61
J 2
(-73 1350);
DISPLAY 0.872340 (-73 1350);
PAINT GREEN (-73 1350);
DISPLAY INVISIBLE (-73 1350);
FORCEPROP 1 LAST HDL_TAP TRUE
J 2
(-400 1225);
DISPLAY 1.234043 (-400 1225);
PAINT GREEN (-400 1225);
DISPLAY INVISIBLE (-400 1225);
FORCEPROP 1 LAST BODY_TYPE PLUMBING
J 2
(-75 1300);
DISPLAY 1.234043 (-75 1300);
PAINT GREEN (-75 1300);
DISPLAY INVISIBLE (-75 1300);
FORCEPROP 2 LAST CDS_LIB mstr_standard
J 2
(-75 1350);
DISPLAY 0.787234 (-75 1350);
PAINT MONO (-75 1350);
DISPLAY INVISIBLE (-75 1350);
FORCEADD TAP..6
R 2
(-75 1450);
FORCEPROP 3 LASTPIN (-125 1450) SIG_NAME M_B_DQ<7>
J 0
(-115 1460);
DISPLAY 0.659574 (-115 1460);
PAINT MONO (-115 1460);
DISPLAY INVISIBLE (-115 1460);
FORCEPROP 1 LASTPIN (-125 1450) BN 7
J 2
(-75 1460);
DISPLAY 0.617021 (-75 1460);
PAINT PINK (-75 1460);
FORCEPROP 1 LAST PATH I62
J 2
(-73 1450);
DISPLAY 0.872340 (-73 1450);
PAINT GREEN (-73 1450);
DISPLAY INVISIBLE (-73 1450);
FORCEPROP 1 LAST HDL_TAP TRUE
J 2
(-400 1325);
DISPLAY 1.234043 (-400 1325);
PAINT GREEN (-400 1325);
DISPLAY INVISIBLE (-400 1325);
FORCEPROP 1 LAST BODY_TYPE PLUMBING
J 2
(-75 1400);
DISPLAY 1.234043 (-75 1400);
PAINT GREEN (-75 1400);
DISPLAY INVISIBLE (-75 1400);
FORCEPROP 2 LAST CDS_LIB mstr_standard
J 2
(-75 1450);
DISPLAY 0.787234 (-75 1450);
PAINT MONO (-75 1450);
DISPLAY INVISIBLE (-75 1450);
FORCEADD TAP..6
R 2
(-75 1550);
FORCEPROP 3 LASTPIN (-125 1550) SIG_NAME M_B_DQ<9>
J 0
(-115 1560);
DISPLAY 0.659574 (-115 1560);
PAINT MONO (-115 1560);
DISPLAY INVISIBLE (-115 1560);
FORCEPROP 1 LASTPIN (-125 1550) BN 9
J 2
(-75 1560);
DISPLAY 0.617021 (-75 1560);
PAINT PINK (-75 1560);
FORCEPROP 1 LAST PATH I63
J 2
(-73 1550);
DISPLAY 0.872340 (-73 1550);
PAINT GREEN (-73 1550);
DISPLAY INVISIBLE (-73 1550);
FORCEPROP 1 LAST HDL_TAP TRUE
J 2
(-400 1425);
DISPLAY 1.234043 (-400 1425);
PAINT GREEN (-400 1425);
DISPLAY INVISIBLE (-400 1425);
FORCEPROP 1 LAST BODY_TYPE PLUMBING
J 2
(-75 1500);
DISPLAY 1.234043 (-75 1500);
PAINT GREEN (-75 1500);
DISPLAY INVISIBLE (-75 1500);
FORCEPROP 2 LAST CDS_LIB mstr_standard
J 2
(-75 1550);
DISPLAY 0.787234 (-75 1550);
PAINT MONO (-75 1550);
DISPLAY INVISIBLE (-75 1550);
FORCEADD TAP..6
R 2
(-75 1500);
FORCEPROP 3 LASTPIN (-125 1500) SIG_NAME M_B_DQ<8>
J 0
(-115 1510);
DISPLAY 0.659574 (-115 1510);
PAINT MONO (-115 1510);
DISPLAY INVISIBLE (-115 1510);
FORCEPROP 1 LASTPIN (-125 1500) BN 8
J 2
(-75 1510);
DISPLAY 0.617021 (-75 1510);
PAINT PINK (-75 1510);
FORCEPROP 1 LAST PATH I64
J 2
(-73 1500);
DISPLAY 0.872340 (-73 1500);
PAINT GREEN (-73 1500);
DISPLAY INVISIBLE (-73 1500);
FORCEPROP 1 LAST HDL_TAP TRUE
J 2
(-400 1375);
DISPLAY 1.234043 (-400 1375);
PAINT GREEN (-400 1375);
DISPLAY INVISIBLE (-400 1375);
FORCEPROP 1 LAST BODY_TYPE PLUMBING
J 2
(-75 1450);
DISPLAY 1.234043 (-75 1450);
PAINT GREEN (-75 1450);
DISPLAY INVISIBLE (-75 1450);
FORCEPROP 2 LAST CDS_LIB mstr_standard
J 2
(-75 1500);
DISPLAY 0.787234 (-75 1500);
PAINT MONO (-75 1500);
DISPLAY INVISIBLE (-75 1500);
FORCEADD TAP..6
R 2
(-75 1650);
FORCEPROP 3 LASTPIN (-125 1650) SIG_NAME M_B_DQ<11>
J 0
(-115 1660);
DISPLAY 0.659574 (-115 1660);
PAINT MONO (-115 1660);
DISPLAY INVISIBLE (-115 1660);
FORCEPROP 1 LASTPIN (-125 1650) BN 11
J 2
(-75 1660);
DISPLAY 0.617021 (-75 1660);
PAINT PINK (-75 1660);
FORCEPROP 1 LAST PATH I65
J 2
(-73 1650);
DISPLAY 0.872340 (-73 1650);
PAINT GREEN (-73 1650);
DISPLAY INVISIBLE (-73 1650);
FORCEPROP 1 LAST HDL_TAP TRUE
J 2
(-400 1525);
DISPLAY 1.234043 (-400 1525);
PAINT GREEN (-400 1525);
DISPLAY INVISIBLE (-400 1525);
FORCEPROP 1 LAST BODY_TYPE PLUMBING
J 2
(-75 1600);
DISPLAY 1.234043 (-75 1600);
PAINT GREEN (-75 1600);
DISPLAY INVISIBLE (-75 1600);
FORCEPROP 2 LAST CDS_LIB mstr_standard
J 2
(-75 1650);
DISPLAY 0.787234 (-75 1650);
PAINT MONO (-75 1650);
DISPLAY INVISIBLE (-75 1650);
FORCEADD TAP..6
R 2
(-75 1600);
FORCEPROP 3 LASTPIN (-125 1600) SIG_NAME M_B_DQ<10>
J 0
(-115 1610);
DISPLAY 0.659574 (-115 1610);
PAINT MONO (-115 1610);
DISPLAY INVISIBLE (-115 1610);
FORCEPROP 1 LASTPIN (-125 1600) BN 10
J 2
(-75 1610);
DISPLAY 0.617021 (-75 1610);
PAINT PINK (-75 1610);
FORCEPROP 1 LAST PATH I66
J 2
(-73 1600);
DISPLAY 0.872340 (-73 1600);
PAINT GREEN (-73 1600);
DISPLAY INVISIBLE (-73 1600);
FORCEPROP 1 LAST HDL_TAP TRUE
J 2
(-400 1475);
DISPLAY 1.234043 (-400 1475);
PAINT GREEN (-400 1475);
DISPLAY INVISIBLE (-400 1475);
FORCEPROP 1 LAST BODY_TYPE PLUMBING
J 2
(-75 1550);
DISPLAY 1.234043 (-75 1550);
PAINT GREEN (-75 1550);
DISPLAY INVISIBLE (-75 1550);
FORCEPROP 2 LAST CDS_LIB mstr_standard
J 2
(-75 1600);
DISPLAY 0.787234 (-75 1600);
PAINT MONO (-75 1600);
DISPLAY INVISIBLE (-75 1600);
FORCEADD SCONN288_H44441003..4
(1675 1650);
FORCEPROP 2 LASTPIN (2175 2500) $PN 1
J 0
(2185 2510);
DISPLAY 0.617021 (2185 2510);
PAINT ORANGE (2185 2510);
FORCEPROP 2 LASTPIN (1175 800) $PN 236
J 2
(1165 810);
DISPLAY 0.617021 (1165 810);
PAINT ORANGE (1165 810);
FORCEPROP 2 LASTPIN (1175 850) $PN 233
J 2
(1165 860);
DISPLAY 0.617021 (1165 860);
PAINT ORANGE (1165 860);
FORCEPROP 2 LASTPIN (1175 900) $PN 231
J 2
(1165 910);
DISPLAY 0.617021 (1165 910);
PAINT ORANGE (1165 910);
FORCEPROP 2 LASTPIN (1175 950) $PN 229
J 2
(1165 960);
DISPLAY 0.617021 (1165 960);
PAINT ORANGE (1165 960);
FORCEPROP 2 LASTPIN (1175 1000) $PN 226
J 2
(1165 1010);
DISPLAY 0.617021 (1165 1010);
PAINT ORANGE (1165 1010);
FORCEPROP 2 LASTPIN (1175 1050) $PN 223
J 2
(1165 1060);
DISPLAY 0.617021 (1165 1060);
PAINT ORANGE (1165 1060);
FORCEPROP 2 LASTPIN (1175 1100) $PN 220
J 2
(1165 1110);
DISPLAY 0.617021 (1165 1110);
PAINT ORANGE (1165 1110);
FORCEPROP 2 LASTPIN (1175 1150) $PN 217
J 2
(1165 1160);
DISPLAY 0.617021 (1165 1160);
PAINT ORANGE (1165 1160);
FORCEPROP 2 LASTPIN (1175 1200) $PN 215
J 2
(1165 1210);
DISPLAY 0.617021 (1165 1210);
PAINT ORANGE (1165 1210);
FORCEPROP 2 LASTPIN (1175 1250) $PN 212
J 2
(1165 1260);
DISPLAY 0.617021 (1165 1260);
PAINT ORANGE (1165 1260);
FORCEPROP 2 LASTPIN (1175 1300) $PN 209
J 2
(1165 1310);
DISPLAY 0.617021 (1165 1310);
PAINT ORANGE (1165 1310);
FORCEPROP 2 LASTPIN (1175 1350) $PN 206
J 2
(1165 1360);
DISPLAY 0.617021 (1165 1360);
PAINT ORANGE (1165 1360);
FORCEPROP 2 LASTPIN (1175 1400) $PN 204
J 2
(1165 1410);
DISPLAY 0.617021 (1165 1410);
PAINT ORANGE (1165 1410);
FORCEPROP 2 LASTPIN (1175 1450) $PN 92
J 2
(1165 1460);
DISPLAY 0.617021 (1165 1460);
PAINT ORANGE (1165 1460);
FORCEPROP 2 LASTPIN (1175 1500) $PN 90
J 2
(1165 1510);
DISPLAY 0.617021 (1165 1510);
PAINT ORANGE (1165 1510);
FORCEPROP 2 LASTPIN (1175 1550) $PN 88
J 2
(1165 1560);
DISPLAY 0.617021 (1165 1560);
PAINT ORANGE (1165 1560);
FORCEPROP 2 LASTPIN (1175 1600) $PN 85
J 2
(1165 1610);
DISPLAY 0.617021 (1165 1610);
PAINT ORANGE (1165 1610);
FORCEPROP 2 LASTPIN (1175 1650) $PN 83
J 2
(1165 1660);
DISPLAY 0.617021 (1165 1660);
PAINT ORANGE (1165 1660);
FORCEPROP 2 LASTPIN (1175 1700) $PN 80
J 2
(1165 1710);
DISPLAY 0.617021 (1165 1710);
PAINT ORANGE (1165 1710);
FORCEPROP 2 LASTPIN (1175 1750) $PN 76
J 2
(1165 1760);
DISPLAY 0.617021 (1165 1760);
PAINT ORANGE (1165 1760);
FORCEPROP 2 LASTPIN (1175 1800) $PN 73
J 2
(1165 1810);
DISPLAY 0.617021 (1165 1810);
PAINT ORANGE (1165 1810);
FORCEPROP 2 LASTPIN (1175 1850) $PN 70
J 2
(1165 1860);
DISPLAY 0.617021 (1165 1860);
PAINT ORANGE (1165 1860);
FORCEPROP 2 LASTPIN (1175 1900) $PN 67
J 2
(1165 1910);
DISPLAY 0.617021 (1165 1910);
PAINT ORANGE (1165 1910);
FORCEPROP 2 LASTPIN (1175 1950) $PN 64
J 2
(1165 1960);
DISPLAY 0.617021 (1165 1960);
PAINT ORANGE (1165 1960);
FORCEPROP 2 LASTPIN (1175 2000) $PN 61
J 2
(1165 2010);
DISPLAY 0.617021 (1165 2010);
PAINT ORANGE (1165 2010);
FORCEPROP 2 LASTPIN (1175 2050) $PN 59
J 2
(1165 2060);
DISPLAY 0.617021 (1165 2060);
PAINT ORANGE (1165 2060);
FORCEPROP 2 LASTPIN (1175 2300) $PN 287
J 2
(1165 2310);
DISPLAY 0.617021 (1165 2310);
PAINT ORANGE (1165 2310);
FORCEPROP 2 LASTPIN (1175 2350) $PN 286
J 2
(1165 2360);
DISPLAY 0.617021 (1165 2360);
PAINT ORANGE (1165 2360);
FORCEPROP 2 LASTPIN (1175 2400) $PN 288
J 2
(1165 2410);
DISPLAY 0.617021 (1165 2410);
PAINT ORANGE (1165 2410);
FORCEPROP 2 LASTPIN (1175 2450) $PN 143
J 2
(1165 2460);
DISPLAY 0.617021 (1165 2460);
PAINT ORANGE (1165 2460);
FORCEPROP 2 LASTPIN (1175 2500) $PN 142
J 2
(1165 2510);
DISPLAY 0.617021 (1165 2510);
PAINT ORANGE (1165 2510);
FORCEPROP 2 LASTPIN (1175 2150) $PN 221
J 2
(1165 2160);
DISPLAY 0.617021 (1165 2160);
PAINT ORANGE (1165 2160);
FORCEPROP 2 LASTPIN (1175 2200) $PN 77
J 2
(1165 2210);
DISPLAY 0.617021 (1165 2210);
PAINT ORANGE (1165 2210);
FORCEPROP 1 LAST MATERIAL SCONN
J 0
(1225 2700);
DISPLAY 0.617021 (1225 2700);
PAINT SKYBLUE (1225 2700);
FORCEPROP 1 LAST PART_NUMBER H44441-003
J 0
(1225 600);
DISPLAY 0.617021 (1225 600);
PAINT BLUE (1225 600);
FORCEPROP 1 LAST LOCATION J6U1
J 0
(1225 2750);
DISPLAY 0.617021 (1225 2750);
PAINT AQUA (1225 2750);
FORCEPROP 2 LASTPIN (2175 2450) $PN 145
J 0
(2185 2460);
DISPLAY 0.617021 (2185 2460);
PAINT ORANGE (2185 2460);
FORCEPROP 0 LAST BOM_SS NOPOP
J 0
(1395 2746);
DISPLAY 1.021277 (1395 2746);
PAINT BROWN (1395 2746);
DISPLAY BOTH (1395 2746);
FORCEPROP 2 LAST ROOM DDR4_CH_B
J 0
(1675 1650);
PAINT ORANGE (1675 1650);
DISPLAY INVISIBLE (1675 1650);
FORCEPROP 1 LAST PATH I67
J 0
(1675 2700);
PAINT GREEN (1675 2700);
DISPLAY INVISIBLE (1675 2700);
FORCEPROP 2 LAST CDS_LOCATION J6U1
J 0
(1225 2750);
DISPLAY 0.617021 (1225 2750);
PAINT AQUA (1225 2750);
DISPLAY INVISIBLE (1225 2750);
FORCEPROP 2 LAST SEC 4
J 0
(1225 2800);
DISPLAY 0.680851 (1225 2800);
PAINT MONO (1225 2800);
DISPLAY INVISIBLE (1225 2800);
FORCEPROP 2 LAST SEC_TYPE PIP
J 0
(1225 2800);
DISPLAY 1.021277 (1225 2800);
PAINT ORANGE (1225 2800);
DISPLAY INVISIBLE (1225 2800);
FORCEPROP 2 LAST CDS_LIB mstr_sconn
J 0
(1675 1650);
PAINT ORANGE (1675 1650);
DISPLAY INVISIBLE (1675 1650);
FORCEPROP 2 LAST BOM_COST MEM
J 0
(1675 1650);
PAINT ORANGE (1675 1650);
DISPLAY INVISIBLE (1675 1650);
FORCEPROP 1 LAST PACK_TYPE PIP
J 0
(1225 2800);
PAINT SKYBLUE (1225 2800);
DISPLAY INVISIBLE (1225 2800);
FORCEADD TAP..6
R 2
(-75 1700);
FORCEPROP 3 LASTPIN (-125 1700) SIG_NAME M_B_DQ<12>
J 0
(-115 1710);
DISPLAY 0.659574 (-115 1710);
PAINT MONO (-115 1710);
DISPLAY INVISIBLE (-115 1710);
FORCEPROP 1 LASTPIN (-125 1700) BN 12
J 2
(-75 1710);
DISPLAY 0.617021 (-75 1710);
PAINT PINK (-75 1710);
FORCEPROP 1 LAST PATH I68
J 2
(-73 1700);
DISPLAY 0.872340 (-73 1700);
PAINT GREEN (-73 1700);
DISPLAY INVISIBLE (-73 1700);
FORCEPROP 1 LAST HDL_TAP TRUE
J 2
(-400 1575);
DISPLAY 1.234043 (-400 1575);
PAINT GREEN (-400 1575);
DISPLAY INVISIBLE (-400 1575);
FORCEPROP 1 LAST BODY_TYPE PLUMBING
J 2
(-75 1650);
DISPLAY 1.234043 (-75 1650);
PAINT GREEN (-75 1650);
DISPLAY INVISIBLE (-75 1650);
FORCEPROP 2 LAST CDS_LIB mstr_standard
J 2
(-75 1700);
DISPLAY 0.787234 (-75 1700);
PAINT MONO (-75 1700);
DISPLAY INVISIBLE (-75 1700);
FORCEADD TAP..6
R 2
(-75 1800);
FORCEPROP 3 LASTPIN (-125 1800) SIG_NAME M_B_DQ<14>
J 0
(-115 1810);
DISPLAY 0.659574 (-115 1810);
PAINT MONO (-115 1810);
DISPLAY INVISIBLE (-115 1810);
FORCEPROP 1 LASTPIN (-125 1800) BN 14
J 2
(-75 1810);
DISPLAY 0.617021 (-75 1810);
PAINT PINK (-75 1810);
FORCEPROP 1 LAST PATH I69
J 2
(-73 1800);
DISPLAY 0.872340 (-73 1800);
PAINT GREEN (-73 1800);
DISPLAY INVISIBLE (-73 1800);
FORCEPROP 1 LAST HDL_TAP TRUE
J 2
(-400 1675);
DISPLAY 1.234043 (-400 1675);
PAINT GREEN (-400 1675);
DISPLAY INVISIBLE (-400 1675);
FORCEPROP 1 LAST BODY_TYPE PLUMBING
J 2
(-75 1750);
DISPLAY 1.234043 (-75 1750);
PAINT GREEN (-75 1750);
DISPLAY INVISIBLE (-75 1750);
FORCEPROP 2 LAST CDS_LIB mstr_standard
J 2
(-75 1800);
DISPLAY 0.787234 (-75 1800);
PAINT MONO (-75 1800);
DISPLAY INVISIBLE (-75 1800);
FORCEADD OFFPAGE..1
(-2375 1550);
FORCEPROP 2 LAST $XR1 45 
J 0
(-2716 1550);
DISPLAY 0.638298 (-2716 1550);
PAINT MONO (-2716 1550);
FORCEPROP 2 LAST $XR0 24 
J 0
(-2626 1550);
DISPLAY 0.638298 (-2626 1550);
PAINT MONO (-2626 1550);
FORCEPROP 2 LAST PATH I7
J 0
(-2575 1600);
DISPLAY 1.021277 (-2575 1600);
PAINT ORANGE (-2575 1600);
DISPLAY INVISIBLE (-2575 1600);
FORCEPROP 1 LAST COMMENT_BODY TRUE
J 0
(-2250 1450);
DISPLAY 0.936170 (-2250 1450);
PAINT GREEN (-2250 1450);
DISPLAY INVISIBLE (-2250 1450);
FORCEPROP 1 LAST OFFPAGE TRUE
J 0
(-2050 1425);
DISPLAY 0.936170 (-2050 1425);
PAINT GREEN (-2050 1425);
DISPLAY INVISIBLE (-2050 1425);
FORCEPROP 2 LAST CDS_LIB mstr_standard
J 0
(-2375 1550);
DISPLAY 0.787234 (-2375 1550);
PAINT MONO (-2375 1550);
DISPLAY INVISIBLE (-2375 1550);
FORCEADD TAP..6
R 2
(-75 1750);
FORCEPROP 3 LASTPIN (-125 1750) SIG_NAME M_B_DQ<13>
J 0
(-115 1760);
DISPLAY 0.659574 (-115 1760);
PAINT MONO (-115 1760);
DISPLAY INVISIBLE (-115 1760);
FORCEPROP 1 LASTPIN (-125 1750) BN 13
J 2
(-75 1760);
DISPLAY 0.617021 (-75 1760);
PAINT PINK (-75 1760);
FORCEPROP 1 LAST PATH I70
J 2
(-73 1750);
DISPLAY 0.872340 (-73 1750);
PAINT GREEN (-73 1750);
DISPLAY INVISIBLE (-73 1750);
FORCEPROP 1 LAST HDL_TAP TRUE
J 2
(-400 1625);
DISPLAY 1.234043 (-400 1625);
PAINT GREEN (-400 1625);
DISPLAY INVISIBLE (-400 1625);
FORCEPROP 1 LAST BODY_TYPE PLUMBING
J 2
(-75 1700);
DISPLAY 1.234043 (-75 1700);
PAINT GREEN (-75 1700);
DISPLAY INVISIBLE (-75 1700);
FORCEPROP 2 LAST CDS_LIB mstr_standard
J 2
(-75 1750);
DISPLAY 0.787234 (-75 1750);
PAINT MONO (-75 1750);
DISPLAY INVISIBLE (-75 1750);
FORCEADD TAP..6
R 2
(-75 1900);
FORCEPROP 3 LASTPIN (-125 1900) SIG_NAME M_B_DQ<16>
J 0
(-115 1910);
DISPLAY 0.659574 (-115 1910);
PAINT MONO (-115 1910);
DISPLAY INVISIBLE (-115 1910);
FORCEPROP 1 LASTPIN (-125 1900) BN 16
J 2
(-75 1910);
DISPLAY 0.617021 (-75 1910);
PAINT PINK (-75 1910);
FORCEPROP 1 LAST PATH I71
J 2
(-73 1900);
DISPLAY 0.872340 (-73 1900);
PAINT GREEN (-73 1900);
DISPLAY INVISIBLE (-73 1900);
FORCEPROP 1 LAST HDL_TAP TRUE
J 2
(-400 1775);
DISPLAY 1.234043 (-400 1775);
PAINT GREEN (-400 1775);
DISPLAY INVISIBLE (-400 1775);
FORCEPROP 1 LAST BODY_TYPE PLUMBING
J 2
(-75 1850);
DISPLAY 1.234043 (-75 1850);
PAINT GREEN (-75 1850);
DISPLAY INVISIBLE (-75 1850);
FORCEPROP 2 LAST CDS_LIB mstr_standard
J 2
(-75 1900);
DISPLAY 0.787234 (-75 1900);
PAINT MONO (-75 1900);
DISPLAY INVISIBLE (-75 1900);
FORCEADD TAP..6
R 2
(-75 1850);
FORCEPROP 3 LASTPIN (-125 1850) SIG_NAME M_B_DQ<15>
J 0
(-115 1860);
DISPLAY 0.659574 (-115 1860);
PAINT MONO (-115 1860);
DISPLAY INVISIBLE (-115 1860);
FORCEPROP 1 LASTPIN (-125 1850) BN 15
J 2
(-75 1860);
DISPLAY 0.617021 (-75 1860);
PAINT PINK (-75 1860);
FORCEPROP 1 LAST PATH I72
J 2
(-73 1850);
DISPLAY 0.872340 (-73 1850);
PAINT GREEN (-73 1850);
DISPLAY INVISIBLE (-73 1850);
FORCEPROP 1 LAST HDL_TAP TRUE
J 2
(-400 1725);
DISPLAY 1.234043 (-400 1725);
PAINT GREEN (-400 1725);
DISPLAY INVISIBLE (-400 1725);
FORCEPROP 1 LAST BODY_TYPE PLUMBING
J 2
(-75 1800);
DISPLAY 1.234043 (-75 1800);
PAINT GREEN (-75 1800);
DISPLAY INVISIBLE (-75 1800);
FORCEPROP 2 LAST CDS_LIB mstr_standard
J 2
(-75 1850);
DISPLAY 0.787234 (-75 1850);
PAINT MONO (-75 1850);
DISPLAY INVISIBLE (-75 1850);
FORCEADD TAP..6
R 2
(-75 1950);
FORCEPROP 3 LASTPIN (-125 1950) SIG_NAME M_B_DQ<17>
J 0
(-115 1960);
DISPLAY 0.659574 (-115 1960);
PAINT MONO (-115 1960);
DISPLAY INVISIBLE (-115 1960);
FORCEPROP 1 LASTPIN (-125 1950) BN 17
J 2
(-75 1960);
DISPLAY 0.617021 (-75 1960);
PAINT PINK (-75 1960);
FORCEPROP 1 LAST PATH I73
J 2
(-73 1950);
DISPLAY 0.872340 (-73 1950);
PAINT GREEN (-73 1950);
DISPLAY INVISIBLE (-73 1950);
FORCEPROP 1 LAST HDL_TAP TRUE
J 2
(-400 1825);
DISPLAY 1.234043 (-400 1825);
PAINT GREEN (-400 1825);
DISPLAY INVISIBLE (-400 1825);
FORCEPROP 1 LAST BODY_TYPE PLUMBING
J 2
(-75 1900);
DISPLAY 1.234043 (-75 1900);
PAINT GREEN (-75 1900);
DISPLAY INVISIBLE (-75 1900);
FORCEPROP 2 LAST CDS_LIB mstr_standard
J 2
(-75 1950);
DISPLAY 0.787234 (-75 1950);
PAINT MONO (-75 1950);
DISPLAY INVISIBLE (-75 1950);
FORCEADD TAP..6
R 2
(-75 2000);
FORCEPROP 3 LASTPIN (-125 2000) SIG_NAME M_B_DQ<18>
J 0
(-115 2010);
DISPLAY 0.659574 (-115 2010);
PAINT MONO (-115 2010);
DISPLAY INVISIBLE (-115 2010);
FORCEPROP 1 LASTPIN (-125 2000) BN 18
J 2
(-75 2010);
DISPLAY 0.617021 (-75 2010);
PAINT PINK (-75 2010);
FORCEPROP 1 LAST PATH I74
J 2
(-73 2000);
DISPLAY 0.872340 (-73 2000);
PAINT GREEN (-73 2000);
DISPLAY INVISIBLE (-73 2000);
FORCEPROP 1 LAST HDL_TAP TRUE
J 2
(-400 1875);
DISPLAY 1.234043 (-400 1875);
PAINT GREEN (-400 1875);
DISPLAY INVISIBLE (-400 1875);
FORCEPROP 1 LAST BODY_TYPE PLUMBING
J 2
(-75 1950);
DISPLAY 1.234043 (-75 1950);
PAINT GREEN (-75 1950);
DISPLAY INVISIBLE (-75 1950);
FORCEPROP 2 LAST CDS_LIB mstr_standard
J 2
(-75 2000);
DISPLAY 0.787234 (-75 2000);
PAINT MONO (-75 2000);
DISPLAY INVISIBLE (-75 2000);
FORCEADD TAP..6
R 2
(-75 2050);
FORCEPROP 3 LASTPIN (-125 2050) SIG_NAME M_B_DQ<19>
J 0
(-115 2060);
DISPLAY 0.659574 (-115 2060);
PAINT MONO (-115 2060);
DISPLAY INVISIBLE (-115 2060);
FORCEPROP 1 LASTPIN (-125 2050) BN 19
J 2
(-75 2060);
DISPLAY 0.617021 (-75 2060);
PAINT PINK (-75 2060);
FORCEPROP 1 LAST PATH I75
J 2
(-73 2050);
DISPLAY 0.872340 (-73 2050);
PAINT GREEN (-73 2050);
DISPLAY INVISIBLE (-73 2050);
FORCEPROP 1 LAST HDL_TAP TRUE
J 2
(-400 1925);
DISPLAY 1.234043 (-400 1925);
PAINT GREEN (-400 1925);
DISPLAY INVISIBLE (-400 1925);
FORCEPROP 1 LAST BODY_TYPE PLUMBING
J 2
(-75 2000);
DISPLAY 1.234043 (-75 2000);
PAINT GREEN (-75 2000);
DISPLAY INVISIBLE (-75 2000);
FORCEPROP 2 LAST CDS_LIB mstr_standard
J 2
(-75 2050);
DISPLAY 0.787234 (-75 2050);
PAINT MONO (-75 2050);
DISPLAY INVISIBLE (-75 2050);
FORCEADD TAP..6
R 2
(-75 2100);
FORCEPROP 3 LASTPIN (-125 2100) SIG_NAME M_B_DQ<20>
J 0
(-115 2110);
DISPLAY 0.659574 (-115 2110);
PAINT MONO (-115 2110);
DISPLAY INVISIBLE (-115 2110);
FORCEPROP 1 LASTPIN (-125 2100) BN 20
J 2
(-75 2110);
DISPLAY 0.617021 (-75 2110);
PAINT PINK (-75 2110);
FORCEPROP 1 LAST PATH I76
J 2
(-73 2100);
DISPLAY 0.872340 (-73 2100);
PAINT GREEN (-73 2100);
DISPLAY INVISIBLE (-73 2100);
FORCEPROP 1 LAST HDL_TAP TRUE
J 2
(-400 1975);
DISPLAY 1.234043 (-400 1975);
PAINT GREEN (-400 1975);
DISPLAY INVISIBLE (-400 1975);
FORCEPROP 1 LAST BODY_TYPE PLUMBING
J 2
(-75 2050);
DISPLAY 1.234043 (-75 2050);
PAINT GREEN (-75 2050);
DISPLAY INVISIBLE (-75 2050);
FORCEPROP 2 LAST CDS_LIB mstr_standard
J 2
(-75 2100);
DISPLAY 0.787234 (-75 2100);
PAINT MONO (-75 2100);
DISPLAY INVISIBLE (-75 2100);
FORCEADD TAP..6
R 2
(-75 2200);
FORCEPROP 3 LASTPIN (-125 2200) SIG_NAME M_B_DQ<22>
J 0
(-115 2210);
DISPLAY 0.659574 (-115 2210);
PAINT MONO (-115 2210);
DISPLAY INVISIBLE (-115 2210);
FORCEPROP 1 LASTPIN (-125 2200) BN 22
J 2
(-75 2210);
DISPLAY 0.617021 (-75 2210);
PAINT PINK (-75 2210);
FORCEPROP 1 LAST PATH I77
J 2
(-73 2200);
DISPLAY 0.872340 (-73 2200);
PAINT GREEN (-73 2200);
DISPLAY INVISIBLE (-73 2200);
FORCEPROP 1 LAST HDL_TAP TRUE
J 2
(-400 2075);
DISPLAY 1.234043 (-400 2075);
PAINT GREEN (-400 2075);
DISPLAY INVISIBLE (-400 2075);
FORCEPROP 1 LAST BODY_TYPE PLUMBING
J 2
(-75 2150);
DISPLAY 1.234043 (-75 2150);
PAINT GREEN (-75 2150);
DISPLAY INVISIBLE (-75 2150);
FORCEPROP 2 LAST CDS_LIB mstr_standard
J 2
(-75 2200);
DISPLAY 0.787234 (-75 2200);
PAINT MONO (-75 2200);
DISPLAY INVISIBLE (-75 2200);
FORCEADD TAP..6
R 2
(-75 2150);
FORCEPROP 3 LASTPIN (-125 2150) SIG_NAME M_B_DQ<21>
J 0
(-115 2160);
DISPLAY 0.659574 (-115 2160);
PAINT MONO (-115 2160);
DISPLAY INVISIBLE (-115 2160);
FORCEPROP 1 LASTPIN (-125 2150) BN 21
J 2
(-75 2160);
DISPLAY 0.617021 (-75 2160);
PAINT PINK (-75 2160);
FORCEPROP 1 LAST PATH I78
J 2
(-73 2150);
DISPLAY 0.872340 (-73 2150);
PAINT GREEN (-73 2150);
DISPLAY INVISIBLE (-73 2150);
FORCEPROP 1 LAST HDL_TAP TRUE
J 2
(-400 2025);
DISPLAY 1.234043 (-400 2025);
PAINT GREEN (-400 2025);
DISPLAY INVISIBLE (-400 2025);
FORCEPROP 1 LAST BODY_TYPE PLUMBING
J 2
(-75 2100);
DISPLAY 1.234043 (-75 2100);
PAINT GREEN (-75 2100);
DISPLAY INVISIBLE (-75 2100);
FORCEPROP 2 LAST CDS_LIB mstr_standard
J 2
(-75 2150);
DISPLAY 0.787234 (-75 2150);
PAINT MONO (-75 2150);
DISPLAY INVISIBLE (-75 2150);
FORCEADD TAP..6
R 2
(-75 2250);
FORCEPROP 3 LASTPIN (-125 2250) SIG_NAME M_B_DQ<23>
J 0
(-115 2260);
DISPLAY 0.659574 (-115 2260);
PAINT MONO (-115 2260);
DISPLAY INVISIBLE (-115 2260);
FORCEPROP 1 LASTPIN (-125 2250) BN 23
J 2
(-75 2260);
DISPLAY 0.617021 (-75 2260);
PAINT PINK (-75 2260);
FORCEPROP 1 LAST PATH I79
J 2
(-73 2250);
DISPLAY 0.872340 (-73 2250);
PAINT GREEN (-73 2250);
DISPLAY INVISIBLE (-73 2250);
FORCEPROP 1 LAST HDL_TAP TRUE
J 2
(-400 2125);
DISPLAY 1.234043 (-400 2125);
PAINT GREEN (-400 2125);
DISPLAY INVISIBLE (-400 2125);
FORCEPROP 1 LAST BODY_TYPE PLUMBING
J 2
(-75 2200);
DISPLAY 1.234043 (-75 2200);
PAINT GREEN (-75 2200);
DISPLAY INVISIBLE (-75 2200);
FORCEPROP 2 LAST CDS_LIB mstr_standard
J 2
(-75 2250);
DISPLAY 0.787234 (-75 2250);
PAINT MONO (-75 2250);
DISPLAY INVISIBLE (-75 2250);
FORCEADD OFFPAGE..5
(-2550 1950);
FORCEPROP 2 LAST $XR23 94 
J 0
(-3164 1986);
DISPLAY 0.638298 (-3164 1986);
PAINT MONO (-3164 1986);
FORCEPROP 2 LAST $XR22 88 
J 0
(-3074 1986);
DISPLAY 0.638298 (-3074 1986);
PAINT MONO (-3074 1986);
FORCEPROP 2 LAST $XR21 87 
J 0
(-2984 1986);
DISPLAY 0.638298 (-2984 1986);
PAINT MONO (-2984 1986);
FORCEPROP 2 LAST $XR20 86 
J 0
(-2894 1986);
DISPLAY 0.638298 (-2894 1986);
PAINT MONO (-2894 1986);
FORCEPROP 2 LAST $XR19 85 
J 0
(-2804 1986);
DISPLAY 0.638298 (-2804 1986);
PAINT MONO (-2804 1986);
FORCEPROP 2 LAST $XR18 84 
J 0
(-3524 1914);
DISPLAY 0.638298 (-3524 1914);
PAINT MONO (-3524 1914);
FORCEPROP 2 LAST $XR17 83 
J 0
(-3434 1914);
DISPLAY 0.638298 (-3434 1914);
PAINT MONO (-3434 1914);
FORCEPROP 2 LAST $XR16 82 
J 0
(-3344 1914);
DISPLAY 0.638298 (-3344 1914);
PAINT MONO (-3344 1914);
FORCEPROP 2 LAST $XR15 81 
J 0
(-3254 1914);
DISPLAY 0.638298 (-3254 1914);
PAINT MONO (-3254 1914);
FORCEPROP 2 LAST $XR14 80 
J 0
(-3164 1914);
DISPLAY 0.638298 (-3164 1914);
PAINT MONO (-3164 1914);
FORCEPROP 2 LAST $XR13 79 
J 0
(-3074 1914);
DISPLAY 0.638298 (-3074 1914);
PAINT MONO (-3074 1914);
FORCEPROP 2 LAST $XR12 78 
J 0
(-2984 1914);
DISPLAY 0.638298 (-2984 1914);
PAINT MONO (-2984 1914);
FORCEPROP 2 LAST $XR11 77 
J 0
(-2894 1914);
DISPLAY 0.638298 (-2894 1914);
PAINT MONO (-2894 1914);
FORCEPROP 2 LAST $XR10 54 
J 0
(-2804 1914);
DISPLAY 0.638298 (-2804 1914);
PAINT MONO (-2804 1914);
FORCEPROP 2 LAST $XR9 53 
J 0
(-3614 1950);
DISPLAY 0.638298 (-3614 1950);
PAINT MONO (-3614 1950);
FORCEPROP 2 LAST $XR8 52 
J 0
(-3524 1950);
DISPLAY 0.638298 (-3524 1950);
PAINT MONO (-3524 1950);
FORCEPROP 2 LAST $XR7 51 
J 0
(-3434 1950);
DISPLAY 0.638298 (-3434 1950);
PAINT MONO (-3434 1950);
FORCEPROP 2 LAST $XR6 50 
J 0
(-3344 1950);
DISPLAY 0.638298 (-3344 1950);
PAINT MONO (-3344 1950);
FORCEPROP 2 LAST $XR5 49 
J 0
(-3254 1950);
DISPLAY 0.638298 (-3254 1950);
PAINT MONO (-3254 1950);
FORCEPROP 2 LAST $XR4 48 
J 0
(-3164 1950);
DISPLAY 0.638298 (-3164 1950);
PAINT MONO (-3164 1950);
FORCEPROP 2 LAST $XR3 47 
J 0
(-3074 1950);
DISPLAY 0.638298 (-3074 1950);
PAINT MONO (-3074 1950);
FORCEPROP 2 LAST $XR2 45 
J 0
(-2984 1950);
DISPLAY 0.638298 (-2984 1950);
PAINT MONO (-2984 1950);
FORCEPROP 2 LAST $XR1 44 
J 0
(-2894 1950);
DISPLAY 0.638298 (-2894 1950);
PAINT MONO (-2894 1950);
FORCEPROP 2 LAST $XR0 43 
J 0
(-2804 1950);
DISPLAY 0.638298 (-2804 1950);
PAINT MONO (-2804 1950);
FORCEPROP 2 LAST PATH I8
J 0
(-2800 2000);
DISPLAY 1.021277 (-2800 2000);
PAINT ORANGE (-2800 2000);
DISPLAY INVISIBLE (-2800 2000);
FORCEPROP 1 LAST COMMENT_BODY TRUE
J 0
(-2450 1875);
DISPLAY 1.404255 (-2450 1875);
PAINT GREEN (-2450 1875);
DISPLAY INVISIBLE (-2450 1875);
FORCEPROP 1 LAST OFFPAGE TRUE
J 0
(-2225 1825);
DISPLAY 1.404255 (-2225 1825);
PAINT GREEN (-2225 1825);
DISPLAY INVISIBLE (-2225 1825);
FORCEPROP 2 LAST CDS_LIB mstr_standard
J 0
(-2550 1950);
DISPLAY 0.787234 (-2550 1950);
PAINT MONO (-2550 1950);
DISPLAY INVISIBLE (-2550 1950);
FORCEADD TAP..6
R 2
(-75 2300);
FORCEPROP 3 LASTPIN (-125 2300) SIG_NAME M_B_DQ<24>
J 0
(-115 2310);
DISPLAY 0.659574 (-115 2310);
PAINT MONO (-115 2310);
DISPLAY INVISIBLE (-115 2310);
FORCEPROP 1 LASTPIN (-125 2300) BN 24
J 2
(-75 2310);
DISPLAY 0.617021 (-75 2310);
PAINT PINK (-75 2310);
FORCEPROP 1 LAST PATH I80
J 2
(-73 2300);
DISPLAY 0.872340 (-73 2300);
PAINT GREEN (-73 2300);
DISPLAY INVISIBLE (-73 2300);
FORCEPROP 1 LAST HDL_TAP TRUE
J 2
(-400 2175);
DISPLAY 1.234043 (-400 2175);
PAINT GREEN (-400 2175);
DISPLAY INVISIBLE (-400 2175);
FORCEPROP 1 LAST BODY_TYPE PLUMBING
J 2
(-75 2250);
DISPLAY 1.234043 (-75 2250);
PAINT GREEN (-75 2250);
DISPLAY INVISIBLE (-75 2250);
FORCEPROP 2 LAST CDS_LIB mstr_standard
J 2
(-75 2300);
DISPLAY 0.787234 (-75 2300);
PAINT MONO (-75 2300);
DISPLAY INVISIBLE (-75 2300);
FORCEADD TAP..6
R 2
(-75 2350);
FORCEPROP 3 LASTPIN (-125 2350) SIG_NAME M_B_DQ<25>
J 0
(-115 2360);
DISPLAY 0.659574 (-115 2360);
PAINT MONO (-115 2360);
DISPLAY INVISIBLE (-115 2360);
FORCEPROP 1 LASTPIN (-125 2350) BN 25
J 2
(-75 2360);
DISPLAY 0.617021 (-75 2360);
PAINT PINK (-75 2360);
FORCEPROP 1 LAST PATH I81
J 2
(-73 2350);
DISPLAY 0.872340 (-73 2350);
PAINT GREEN (-73 2350);
DISPLAY INVISIBLE (-73 2350);
FORCEPROP 1 LAST HDL_TAP TRUE
J 2
(-400 2225);
DISPLAY 1.234043 (-400 2225);
PAINT GREEN (-400 2225);
DISPLAY INVISIBLE (-400 2225);
FORCEPROP 1 LAST BODY_TYPE PLUMBING
J 2
(-75 2300);
DISPLAY 1.234043 (-75 2300);
PAINT GREEN (-75 2300);
DISPLAY INVISIBLE (-75 2300);
FORCEPROP 2 LAST CDS_LIB mstr_standard
J 2
(-75 2350);
DISPLAY 0.787234 (-75 2350);
PAINT MONO (-75 2350);
DISPLAY INVISIBLE (-75 2350);
FORCEADD TAP..6
R 2
(-75 2400);
FORCEPROP 3 LASTPIN (-125 2400) SIG_NAME M_B_DQ<26>
J 0
(-115 2410);
DISPLAY 0.659574 (-115 2410);
PAINT MONO (-115 2410);
DISPLAY INVISIBLE (-115 2410);
FORCEPROP 1 LASTPIN (-125 2400) BN 26
J 2
(-75 2410);
DISPLAY 0.617021 (-75 2410);
PAINT PINK (-75 2410);
FORCEPROP 1 LAST PATH I82
J 2
(-73 2400);
DISPLAY 0.872340 (-73 2400);
PAINT GREEN (-73 2400);
DISPLAY INVISIBLE (-73 2400);
FORCEPROP 1 LAST HDL_TAP TRUE
J 2
(-400 2275);
DISPLAY 1.234043 (-400 2275);
PAINT GREEN (-400 2275);
DISPLAY INVISIBLE (-400 2275);
FORCEPROP 1 LAST BODY_TYPE PLUMBING
J 2
(-75 2350);
DISPLAY 1.234043 (-75 2350);
PAINT GREEN (-75 2350);
DISPLAY INVISIBLE (-75 2350);
FORCEPROP 2 LAST CDS_LIB mstr_standard
J 2
(-75 2400);
DISPLAY 0.787234 (-75 2400);
PAINT MONO (-75 2400);
DISPLAY INVISIBLE (-75 2400);
FORCEADD TAP..6
R 2
(-75 2450);
FORCEPROP 3 LASTPIN (-125 2450) SIG_NAME M_B_DQ<27>
J 0
(-115 2460);
DISPLAY 0.659574 (-115 2460);
PAINT MONO (-115 2460);
DISPLAY INVISIBLE (-115 2460);
FORCEPROP 1 LASTPIN (-125 2450) BN 27
J 2
(-75 2460);
DISPLAY 0.617021 (-75 2460);
PAINT PINK (-75 2460);
FORCEPROP 1 LAST PATH I83
J 2
(-73 2450);
DISPLAY 0.872340 (-73 2450);
PAINT GREEN (-73 2450);
DISPLAY INVISIBLE (-73 2450);
FORCEPROP 1 LAST HDL_TAP TRUE
J 2
(-400 2325);
DISPLAY 1.234043 (-400 2325);
PAINT GREEN (-400 2325);
DISPLAY INVISIBLE (-400 2325);
FORCEPROP 1 LAST BODY_TYPE PLUMBING
J 2
(-75 2400);
DISPLAY 1.234043 (-75 2400);
PAINT GREEN (-75 2400);
DISPLAY INVISIBLE (-75 2400);
FORCEPROP 2 LAST CDS_LIB mstr_standard
J 2
(-75 2450);
DISPLAY 0.787234 (-75 2450);
PAINT MONO (-75 2450);
DISPLAY INVISIBLE (-75 2450);
FORCEADD TAP..6
R 2
(-75 2550);
FORCEPROP 3 LASTPIN (-125 2550) SIG_NAME M_B_DQ<29>
J 0
(-115 2560);
DISPLAY 0.659574 (-115 2560);
PAINT MONO (-115 2560);
DISPLAY INVISIBLE (-115 2560);
FORCEPROP 1 LASTPIN (-125 2550) BN 29
J 2
(-75 2560);
DISPLAY 0.617021 (-75 2560);
PAINT PINK (-75 2560);
FORCEPROP 1 LAST PATH I84
J 2
(-73 2550);
DISPLAY 0.872340 (-73 2550);
PAINT GREEN (-73 2550);
DISPLAY INVISIBLE (-73 2550);
FORCEPROP 1 LAST HDL_TAP TRUE
J 2
(-400 2425);
DISPLAY 1.234043 (-400 2425);
PAINT GREEN (-400 2425);
DISPLAY INVISIBLE (-400 2425);
FORCEPROP 1 LAST BODY_TYPE PLUMBING
J 2
(-75 2500);
DISPLAY 1.234043 (-75 2500);
PAINT GREEN (-75 2500);
DISPLAY INVISIBLE (-75 2500);
FORCEPROP 2 LAST CDS_LIB mstr_standard
J 2
(-75 2550);
DISPLAY 0.787234 (-75 2550);
PAINT MONO (-75 2550);
DISPLAY INVISIBLE (-75 2550);
FORCEADD TAP..6
R 2
(-75 2500);
FORCEPROP 3 LASTPIN (-125 2500) SIG_NAME M_B_DQ<28>
J 0
(-115 2510);
DISPLAY 0.659574 (-115 2510);
PAINT MONO (-115 2510);
DISPLAY INVISIBLE (-115 2510);
FORCEPROP 1 LASTPIN (-125 2500) BN 28
J 2
(-75 2510);
DISPLAY 0.617021 (-75 2510);
PAINT PINK (-75 2510);
FORCEPROP 1 LAST PATH I85
J 2
(-73 2500);
DISPLAY 0.872340 (-73 2500);
PAINT GREEN (-73 2500);
DISPLAY INVISIBLE (-73 2500);
FORCEPROP 1 LAST HDL_TAP TRUE
J 2
(-400 2375);
DISPLAY 1.234043 (-400 2375);
PAINT GREEN (-400 2375);
DISPLAY INVISIBLE (-400 2375);
FORCEPROP 1 LAST BODY_TYPE PLUMBING
J 2
(-75 2450);
DISPLAY 1.234043 (-75 2450);
PAINT GREEN (-75 2450);
DISPLAY INVISIBLE (-75 2450);
FORCEPROP 2 LAST CDS_LIB mstr_standard
J 2
(-75 2500);
DISPLAY 0.787234 (-75 2500);
PAINT MONO (-75 2500);
DISPLAY INVISIBLE (-75 2500);
FORCEADD TAP..6
R 2
(-75 2600);
FORCEPROP 3 LASTPIN (-125 2600) SIG_NAME M_B_DQ<30>
J 0
(-115 2610);
DISPLAY 0.659574 (-115 2610);
PAINT MONO (-115 2610);
DISPLAY INVISIBLE (-115 2610);
FORCEPROP 1 LASTPIN (-125 2600) BN 30
J 2
(-75 2610);
DISPLAY 0.617021 (-75 2610);
PAINT PINK (-75 2610);
FORCEPROP 1 LAST PATH I86
J 2
(-73 2600);
DISPLAY 0.872340 (-73 2600);
PAINT GREEN (-73 2600);
DISPLAY INVISIBLE (-73 2600);
FORCEPROP 1 LAST HDL_TAP TRUE
J 2
(-400 2475);
DISPLAY 1.234043 (-400 2475);
PAINT GREEN (-400 2475);
DISPLAY INVISIBLE (-400 2475);
FORCEPROP 1 LAST BODY_TYPE PLUMBING
J 2
(-75 2550);
DISPLAY 1.234043 (-75 2550);
PAINT GREEN (-75 2550);
DISPLAY INVISIBLE (-75 2550);
FORCEPROP 2 LAST CDS_LIB mstr_standard
J 2
(-75 2600);
DISPLAY 0.787234 (-75 2600);
PAINT MONO (-75 2600);
DISPLAY INVISIBLE (-75 2600);
FORCEADD TAP..6
R 2
(-75 2650);
FORCEPROP 3 LASTPIN (-125 2650) SIG_NAME M_B_DQ<31>
J 0
(-115 2660);
DISPLAY 0.659574 (-115 2660);
PAINT MONO (-115 2660);
DISPLAY INVISIBLE (-115 2660);
FORCEPROP 1 LASTPIN (-125 2650) BN 31
J 2
(-75 2660);
DISPLAY 0.617021 (-75 2660);
PAINT PINK (-75 2660);
FORCEPROP 1 LAST PATH I87
J 2
(-73 2650);
DISPLAY 0.872340 (-73 2650);
PAINT GREEN (-73 2650);
DISPLAY INVISIBLE (-73 2650);
FORCEPROP 1 LAST HDL_TAP TRUE
J 2
(-400 2525);
DISPLAY 1.234043 (-400 2525);
PAINT GREEN (-400 2525);
DISPLAY INVISIBLE (-400 2525);
FORCEPROP 1 LAST BODY_TYPE PLUMBING
J 2
(-75 2600);
DISPLAY 1.234043 (-75 2600);
PAINT GREEN (-75 2600);
DISPLAY INVISIBLE (-75 2600);
FORCEPROP 2 LAST CDS_LIB mstr_standard
J 2
(-75 2650);
DISPLAY 0.787234 (-75 2650);
PAINT MONO (-75 2650);
DISPLAY INVISIBLE (-75 2650);
FORCEADD TAP..6
R 2
(-75 2700);
FORCEPROP 3 LASTPIN (-125 2700) SIG_NAME M_B_DQ<32>
J 0
(-115 2710);
DISPLAY 0.659574 (-115 2710);
PAINT MONO (-115 2710);
DISPLAY INVISIBLE (-115 2710);
FORCEPROP 1 LASTPIN (-125 2700) BN 32
J 2
(-75 2710);
DISPLAY 0.617021 (-75 2710);
PAINT PINK (-75 2710);
FORCEPROP 1 LAST PATH I88
J 2
(-73 2700);
DISPLAY 0.872340 (-73 2700);
PAINT GREEN (-73 2700);
DISPLAY INVISIBLE (-73 2700);
FORCEPROP 1 LAST HDL_TAP TRUE
J 2
(-400 2575);
DISPLAY 1.234043 (-400 2575);
PAINT GREEN (-400 2575);
DISPLAY INVISIBLE (-400 2575);
FORCEPROP 1 LAST BODY_TYPE PLUMBING
J 2
(-75 2650);
DISPLAY 1.234043 (-75 2650);
PAINT GREEN (-75 2650);
DISPLAY INVISIBLE (-75 2650);
FORCEPROP 2 LAST CDS_LIB mstr_standard
J 2
(-75 2700);
DISPLAY 0.787234 (-75 2700);
PAINT MONO (-75 2700);
DISPLAY INVISIBLE (-75 2700);
FORCEADD TAP..6
R 2
(-75 2750);
FORCEPROP 3 LASTPIN (-125 2750) SIG_NAME M_B_DQ<33>
J 0
(-115 2760);
DISPLAY 0.659574 (-115 2760);
PAINT MONO (-115 2760);
DISPLAY INVISIBLE (-115 2760);
FORCEPROP 1 LASTPIN (-125 2750) BN 33
J 2
(-75 2760);
DISPLAY 0.617021 (-75 2760);
PAINT PINK (-75 2760);
FORCEPROP 1 LAST PATH I89
J 2
(-73 2750);
DISPLAY 0.872340 (-73 2750);
PAINT GREEN (-73 2750);
DISPLAY INVISIBLE (-73 2750);
FORCEPROP 1 LAST HDL_TAP TRUE
J 2
(-400 2625);
DISPLAY 1.234043 (-400 2625);
PAINT GREEN (-400 2625);
DISPLAY INVISIBLE (-400 2625);
FORCEPROP 1 LAST BODY_TYPE PLUMBING
J 2
(-75 2700);
DISPLAY 1.234043 (-75 2700);
PAINT GREEN (-75 2700);
DISPLAY INVISIBLE (-75 2700);
FORCEPROP 2 LAST CDS_LIB mstr_standard
J 2
(-75 2750);
DISPLAY 0.787234 (-75 2750);
PAINT MONO (-75 2750);
DISPLAY INVISIBLE (-75 2750);
FORCEADD OFFPAGE..1
(-2375 3150);
FORCEPROP 2 LAST $XR1 45 
J 0
(-2686 3150);
DISPLAY 0.638298 (-2686 3150);
PAINT MONO (-2686 3150);
FORCEPROP 2 LAST $XR0 24 
J 0
(-2596 3150);
DISPLAY 0.638298 (-2596 3150);
PAINT MONO (-2596 3150);
FORCEPROP 2 LAST PATH I9
J 0
(-2575 3200);
DISPLAY 1.021277 (-2575 3200);
PAINT ORANGE (-2575 3200);
DISPLAY INVISIBLE (-2575 3200);
FORCEPROP 1 LAST COMMENT_BODY TRUE
J 0
(-2250 3050);
DISPLAY 0.936170 (-2250 3050);
PAINT GREEN (-2250 3050);
DISPLAY INVISIBLE (-2250 3050);
FORCEPROP 1 LAST OFFPAGE TRUE
J 0
(-2050 3025);
DISPLAY 0.936170 (-2050 3025);
PAINT GREEN (-2050 3025);
DISPLAY INVISIBLE (-2050 3025);
FORCEPROP 2 LAST CDS_LIB mstr_standard
J 0
(-2375 3150);
DISPLAY 0.787234 (-2375 3150);
PAINT MONO (-2375 3150);
DISPLAY INVISIBLE (-2375 3150);
FORCEADD TAP..6
R 2
(-75 2800);
FORCEPROP 3 LASTPIN (-125 2800) SIG_NAME M_B_DQ<34>
J 0
(-115 2810);
DISPLAY 0.659574 (-115 2810);
PAINT MONO (-115 2810);
DISPLAY INVISIBLE (-115 2810);
FORCEPROP 1 LASTPIN (-125 2800) BN 34
J 2
(-75 2810);
DISPLAY 0.617021 (-75 2810);
PAINT PINK (-75 2810);
FORCEPROP 1 LAST PATH I90
J 2
(-73 2800);
DISPLAY 0.872340 (-73 2800);
PAINT GREEN (-73 2800);
DISPLAY INVISIBLE (-73 2800);
FORCEPROP 1 LAST HDL_TAP TRUE
J 2
(-400 2675);
DISPLAY 1.234043 (-400 2675);
PAINT GREEN (-400 2675);
DISPLAY INVISIBLE (-400 2675);
FORCEPROP 1 LAST BODY_TYPE PLUMBING
J 2
(-75 2750);
DISPLAY 1.234043 (-75 2750);
PAINT GREEN (-75 2750);
DISPLAY INVISIBLE (-75 2750);
FORCEPROP 2 LAST CDS_LIB mstr_standard
J 2
(-75 2800);
DISPLAY 0.787234 (-75 2800);
PAINT MONO (-75 2800);
DISPLAY INVISIBLE (-75 2800);
FORCEADD TAP..6
R 2
(-75 2850);
FORCEPROP 3 LASTPIN (-125 2850) SIG_NAME M_B_DQ<35>
J 0
(-115 2860);
DISPLAY 0.659574 (-115 2860);
PAINT MONO (-115 2860);
DISPLAY INVISIBLE (-115 2860);
FORCEPROP 1 LASTPIN (-125 2850) BN 35
J 2
(-75 2860);
DISPLAY 0.617021 (-75 2860);
PAINT PINK (-75 2860);
FORCEPROP 1 LAST PATH I91
J 2
(-73 2850);
DISPLAY 0.872340 (-73 2850);
PAINT GREEN (-73 2850);
DISPLAY INVISIBLE (-73 2850);
FORCEPROP 1 LAST HDL_TAP TRUE
J 2
(-400 2725);
DISPLAY 1.234043 (-400 2725);
PAINT GREEN (-400 2725);
DISPLAY INVISIBLE (-400 2725);
FORCEPROP 1 LAST BODY_TYPE PLUMBING
J 2
(-75 2800);
DISPLAY 1.234043 (-75 2800);
PAINT GREEN (-75 2800);
DISPLAY INVISIBLE (-75 2800);
FORCEPROP 2 LAST CDS_LIB mstr_standard
J 2
(-75 2850);
DISPLAY 0.787234 (-75 2850);
PAINT MONO (-75 2850);
DISPLAY INVISIBLE (-75 2850);
FORCEADD TAP..6
R 2
(-75 2900);
FORCEPROP 3 LASTPIN (-125 2900) SIG_NAME M_B_DQ<36>
J 0
(-115 2910);
DISPLAY 0.659574 (-115 2910);
PAINT MONO (-115 2910);
DISPLAY INVISIBLE (-115 2910);
FORCEPROP 1 LASTPIN (-125 2900) BN 36
J 2
(-75 2910);
DISPLAY 0.617021 (-75 2910);
PAINT PINK (-75 2910);
FORCEPROP 1 LAST PATH I92
J 2
(-73 2900);
DISPLAY 0.872340 (-73 2900);
PAINT GREEN (-73 2900);
DISPLAY INVISIBLE (-73 2900);
FORCEPROP 1 LAST HDL_TAP TRUE
J 2
(-400 2775);
DISPLAY 1.234043 (-400 2775);
PAINT GREEN (-400 2775);
DISPLAY INVISIBLE (-400 2775);
FORCEPROP 1 LAST BODY_TYPE PLUMBING
J 2
(-75 2850);
DISPLAY 1.234043 (-75 2850);
PAINT GREEN (-75 2850);
DISPLAY INVISIBLE (-75 2850);
FORCEPROP 2 LAST CDS_LIB mstr_standard
J 2
(-75 2900);
DISPLAY 0.787234 (-75 2900);
PAINT MONO (-75 2900);
DISPLAY INVISIBLE (-75 2900);
FORCEADD TAP..6
R 2
(-75 2950);
FORCEPROP 3 LASTPIN (-125 2950) SIG_NAME M_B_DQ<37>
J 0
(-115 2960);
DISPLAY 0.659574 (-115 2960);
PAINT MONO (-115 2960);
DISPLAY INVISIBLE (-115 2960);
FORCEPROP 1 LASTPIN (-125 2950) BN 37
J 2
(-75 2960);
DISPLAY 0.617021 (-75 2960);
PAINT PINK (-75 2960);
FORCEPROP 1 LAST PATH I93
J 2
(-73 2950);
DISPLAY 0.872340 (-73 2950);
PAINT GREEN (-73 2950);
DISPLAY INVISIBLE (-73 2950);
FORCEPROP 1 LAST HDL_TAP TRUE
J 2
(-400 2825);
DISPLAY 1.234043 (-400 2825);
PAINT GREEN (-400 2825);
DISPLAY INVISIBLE (-400 2825);
FORCEPROP 1 LAST BODY_TYPE PLUMBING
J 2
(-75 2900);
DISPLAY 1.234043 (-75 2900);
PAINT GREEN (-75 2900);
DISPLAY INVISIBLE (-75 2900);
FORCEPROP 2 LAST CDS_LIB mstr_standard
J 2
(-75 2950);
DISPLAY 0.787234 (-75 2950);
PAINT MONO (-75 2950);
DISPLAY INVISIBLE (-75 2950);
FORCEADD TAP..6
R 2
(-75 3100);
FORCEPROP 3 LASTPIN (-125 3100) SIG_NAME M_B_DQ<40>
J 0
(-115 3110);
DISPLAY 0.659574 (-115 3110);
PAINT MONO (-115 3110);
DISPLAY INVISIBLE (-115 3110);
FORCEPROP 1 LASTPIN (-125 3100) BN 40
J 2
(-75 3110);
DISPLAY 0.617021 (-75 3110);
PAINT PINK (-75 3110);
FORCEPROP 1 LAST PATH I94
J 2
(-73 3100);
DISPLAY 0.872340 (-73 3100);
PAINT GREEN (-73 3100);
DISPLAY INVISIBLE (-73 3100);
FORCEPROP 1 LAST HDL_TAP TRUE
J 2
(-400 2975);
DISPLAY 1.234043 (-400 2975);
PAINT GREEN (-400 2975);
DISPLAY INVISIBLE (-400 2975);
FORCEPROP 1 LAST BODY_TYPE PLUMBING
J 2
(-75 3050);
DISPLAY 1.234043 (-75 3050);
PAINT GREEN (-75 3050);
DISPLAY INVISIBLE (-75 3050);
FORCEPROP 2 LAST CDS_LIB mstr_standard
J 2
(-75 3100);
DISPLAY 0.787234 (-75 3100);
PAINT MONO (-75 3100);
DISPLAY INVISIBLE (-75 3100);
FORCEADD TAP..6
R 2
(-75 3000);
FORCEPROP 3 LASTPIN (-125 3000) SIG_NAME M_B_DQ<38>
J 0
(-115 3010);
DISPLAY 0.659574 (-115 3010);
PAINT MONO (-115 3010);
DISPLAY INVISIBLE (-115 3010);
FORCEPROP 1 LASTPIN (-125 3000) BN 38
J 2
(-75 3010);
DISPLAY 0.617021 (-75 3010);
PAINT PINK (-75 3010);
FORCEPROP 1 LAST PATH I95
J 2
(-73 3000);
DISPLAY 0.872340 (-73 3000);
PAINT GREEN (-73 3000);
DISPLAY INVISIBLE (-73 3000);
FORCEPROP 1 LAST HDL_TAP TRUE
J 2
(-400 2875);
DISPLAY 1.234043 (-400 2875);
PAINT GREEN (-400 2875);
DISPLAY INVISIBLE (-400 2875);
FORCEPROP 1 LAST BODY_TYPE PLUMBING
J 2
(-75 2950);
DISPLAY 1.234043 (-75 2950);
PAINT GREEN (-75 2950);
DISPLAY INVISIBLE (-75 2950);
FORCEPROP 2 LAST CDS_LIB mstr_standard
J 2
(-75 3000);
DISPLAY 0.787234 (-75 3000);
PAINT MONO (-75 3000);
DISPLAY INVISIBLE (-75 3000);
FORCEADD TAP..6
R 2
(-75 3050);
FORCEPROP 3 LASTPIN (-125 3050) SIG_NAME M_B_DQ<39>
J 0
(-115 3060);
DISPLAY 0.659574 (-115 3060);
PAINT MONO (-115 3060);
DISPLAY INVISIBLE (-115 3060);
FORCEPROP 1 LASTPIN (-125 3050) BN 39
J 2
(-75 3060);
DISPLAY 0.617021 (-75 3060);
PAINT PINK (-75 3060);
FORCEPROP 1 LAST PATH I96
J 2
(-73 3050);
DISPLAY 0.872340 (-73 3050);
PAINT GREEN (-73 3050);
DISPLAY INVISIBLE (-73 3050);
FORCEPROP 1 LAST HDL_TAP TRUE
J 2
(-400 2925);
DISPLAY 1.234043 (-400 2925);
PAINT GREEN (-400 2925);
DISPLAY INVISIBLE (-400 2925);
FORCEPROP 1 LAST BODY_TYPE PLUMBING
J 2
(-75 3000);
DISPLAY 1.234043 (-75 3000);
PAINT GREEN (-75 3000);
DISPLAY INVISIBLE (-75 3000);
FORCEPROP 2 LAST CDS_LIB mstr_standard
J 2
(-75 3050);
DISPLAY 0.787234 (-75 3050);
PAINT MONO (-75 3050);
DISPLAY INVISIBLE (-75 3050);
FORCEADD TAP..6
R 2
(-75 3200);
FORCEPROP 3 LASTPIN (-125 3200) SIG_NAME M_B_DQ<42>
J 0
(-115 3210);
DISPLAY 0.659574 (-115 3210);
PAINT MONO (-115 3210);
DISPLAY INVISIBLE (-115 3210);
FORCEPROP 1 LASTPIN (-125 3200) BN 42
J 2
(-75 3210);
DISPLAY 0.617021 (-75 3210);
PAINT PINK (-75 3210);
FORCEPROP 1 LAST PATH I97
J 2
(-73 3200);
DISPLAY 0.872340 (-73 3200);
PAINT GREEN (-73 3200);
DISPLAY INVISIBLE (-73 3200);
FORCEPROP 1 LAST HDL_TAP TRUE
J 2
(-400 3075);
DISPLAY 1.234043 (-400 3075);
PAINT GREEN (-400 3075);
DISPLAY INVISIBLE (-400 3075);
FORCEPROP 1 LAST BODY_TYPE PLUMBING
J 2
(-75 3150);
DISPLAY 1.234043 (-75 3150);
PAINT GREEN (-75 3150);
DISPLAY INVISIBLE (-75 3150);
FORCEPROP 2 LAST CDS_LIB mstr_standard
J 2
(-75 3200);
DISPLAY 0.787234 (-75 3200);
PAINT MONO (-75 3200);
DISPLAY INVISIBLE (-75 3200);
FORCEADD TAP..6
R 2
(-75 3150);
FORCEPROP 3 LASTPIN (-125 3150) SIG_NAME M_B_DQ<41>
J 0
(-115 3160);
DISPLAY 0.659574 (-115 3160);
PAINT MONO (-115 3160);
DISPLAY INVISIBLE (-115 3160);
FORCEPROP 1 LASTPIN (-125 3150) BN 41
J 2
(-75 3160);
DISPLAY 0.617021 (-75 3160);
PAINT PINK (-75 3160);
FORCEPROP 1 LAST PATH I98
J 2
(-73 3150);
DISPLAY 0.872340 (-73 3150);
PAINT GREEN (-73 3150);
DISPLAY INVISIBLE (-73 3150);
FORCEPROP 1 LAST HDL_TAP TRUE
J 2
(-400 3025);
DISPLAY 1.234043 (-400 3025);
PAINT GREEN (-400 3025);
DISPLAY INVISIBLE (-400 3025);
FORCEPROP 1 LAST BODY_TYPE PLUMBING
J 2
(-75 3100);
DISPLAY 1.234043 (-75 3100);
PAINT GREEN (-75 3100);
DISPLAY INVISIBLE (-75 3100);
FORCEPROP 2 LAST CDS_LIB mstr_standard
J 2
(-75 3150);
DISPLAY 0.787234 (-75 3150);
PAINT MONO (-75 3150);
DISPLAY INVISIBLE (-75 3150);
FORCEADD TAP..6
R 2
(-75 3300);
FORCEPROP 3 LASTPIN (-125 3300) SIG_NAME M_B_DQ<44>
J 0
(-115 3310);
DISPLAY 0.659574 (-115 3310);
PAINT MONO (-115 3310);
DISPLAY INVISIBLE (-115 3310);
FORCEPROP 1 LASTPIN (-125 3300) BN 44
J 2
(-75 3310);
DISPLAY 0.617021 (-75 3310);
PAINT PINK (-75 3310);
FORCEPROP 1 LAST PATH I99
J 2
(-73 3300);
DISPLAY 0.872340 (-73 3300);
PAINT GREEN (-73 3300);
DISPLAY INVISIBLE (-73 3300);
FORCEPROP 1 LAST HDL_TAP TRUE
J 2
(-400 3175);
DISPLAY 1.234043 (-400 3175);
PAINT GREEN (-400 3175);
DISPLAY INVISIBLE (-400 3175);
FORCEPROP 1 LAST BODY_TYPE PLUMBING
J 2
(-75 3250);
DISPLAY 1.234043 (-75 3250);
PAINT GREEN (-75 3250);
DISPLAY INVISIBLE (-75 3250);
FORCEPROP 2 LAST CDS_LIB mstr_standard
J 2
(-75 3300);
DISPLAY 0.787234 (-75 3300);
PAINT MONO (-75 3300);
DISPLAY INVISIBLE (-75 3300);
FORCEADD INTEL_CORP_BPAGE..1
(4250 200);
FORCEPROP 1 LAST CDS_CON_LAST_MODIFIED Fri Jun 16 17:48:17 2017
J 0
(2825 525);
PAINT ORANGE (2825 525);
DISPLAY INVISIBLE (2825 525);
FORCEPROP 1 LAST CUSTOM_TXT_CDS <CURRENT_DESIGN_SHEET> OF <TOTAL_DESIGN_SHEETS>
J 0
(3750 225);
PAINT ORANGE (3750 225);
FORCEPROP 1 LAST CUSTOM_TXT_CDS <CON_LAST_MODIFIED>
J 0
(250 300);
PAINT ORANGE (250 300);
FORCEPROP 2 LAST CUSTOM_TXT_CDS <XR_PAGE_TITLE>
J 0
(-3640 5450);
DISPLAY 0.638298 (-3640 5450);
PAINT PINK (-3640 5450);
DISPLAY INVISIBLE (-3640 5450);
FORCEPROP 1 LAST SCH_TITLE CPU0 DDR4 CH B DIMM1
J 0
(-3700 250);
DISPLAY 1.212766 (-3700 250);
PAINT ORANGE (-3700 250);
FORCEPROP 1 LAST COMMENT_BODY TRUE
J 0
(4262 212);
DISPLAY 0.468085 (4262 212);
PAINT GREEN (4262 212);
DISPLAY INVISIBLE (4262 212);
FORCEPROP 2 LAST PAGE_BORDER TRUE
J 0
(-3640 5450);
DISPLAY 0.638298 (-3640 5450);
PAINT PINK (-3640 5450);
DISPLAY INVISIBLE (-3640 5450);
FORCEPROP 2 LAST CDS_LIB mstr_symbols
J 0
(4250 200);
PAINT MONO (4250 200);
DISPLAY INVISIBLE (4250 200);
FORCEPROP 2 LAST CDS_XR_PAGE_TITLE CR-46 : @BASEBOARD_FAB2_LIB.BASEBOARD_FAB2(SCH_1):PAGE46
J 0
(-3640 5450);
DISPLAY 0.638298 (-3640 5450);
PAINT PINK (-3640 5450);
DISPLAY INVISIBLE (-3640 5450);
FORCEADD BOM_NOTE..1
(-3450 5000);
FORCEPROP 0 LAST L1 UNSTUFF FOR SKU B
J 0
(-3600 4900);
DISPLAY 1.063830 (-3600 4900);
PAINT WHITE (-3600 4900);
FORCEPROP 2 LAST ROOM SB_HEADERS
J 0
(-3600 4975);
DISPLAY 1.361702 (-3600 4975);
PAINT ORANGE (-3600 4975);
DISPLAY INVISIBLE (-3600 4975);
FORCEPROP 1 LAST COMMENT_BODY TRUE
J 0
(-3425 5100);
DISPLAY 1.319149 (-3425 5100);
PAINT ORANGE (-3425 5100);
DISPLAY INVISIBLE (-3425 5100);
FORCEPROP 2 LAST CDS_LIB mstr_symbols
J 0
(-3450 5000);
PAINT ORANGE (-3450 5000);
DISPLAY INVISIBLE (-3450 5000);
FORCEPROP 2 LAST BOM_COST SB
J 0
(-3600 4975);
DISPLAY 1.361702 (-3600 4975);
PAINT ORANGE (-3600 4975);
DISPLAY INVISIBLE (-3600 4975);
WIRE 16 -1 (-2975 800)(-2975 700);
WIRE 16 -1 (600 2150)(600 2050);
WIRE 16 -1 (600 2050)(975 2050);
WIRE 16 -1 (975 2000)(975 2050);
WIRE 16 -1 (975 2050)(1175 2050);
WIRE 16 -1 (975 1950)(975 2000);
WIRE 16 -1 (975 2000)(1175 2000);
WIRE 16 -1 (975 1900)(975 1950);
WIRE 16 -1 (975 1950)(1175 1950);
WIRE 16 -1 (975 1850)(975 1900);
WIRE 16 -1 (975 1900)(1175 1900);
WIRE 16 -1 (975 1800)(975 1850);
WIRE 16 -1 (975 1850)(1175 1850);
WIRE 16 -1 (975 1750)(975 1800);
WIRE 16 -1 (975 1800)(1175 1800);
WIRE 16 -1 (975 1700)(975 1750);
WIRE 16 -1 (975 1750)(1175 1750);
WIRE 16 -1 (975 1650)(975 1700);
WIRE 16 -1 (975 1700)(1175 1700);
WIRE 16 -1 (975 1600)(975 1650);
WIRE 16 -1 (975 1650)(1175 1650);
WIRE 16 -1 (975 1550)(975 1600);
WIRE 16 -1 (975 1600)(1175 1600);
WIRE 16 -1 (975 1500)(975 1550);
WIRE 16 -1 (975 1550)(1175 1550);
WIRE 16 -1 (975 1450)(975 1500);
WIRE 16 -1 (975 1500)(1175 1500);
WIRE 16 -1 (975 1400)(975 1450);
WIRE 16 -1 (975 1450)(1175 1450);
WIRE 16 -1 (975 1350)(975 1400);
WIRE 16 -1 (975 1400)(1175 1400);
WIRE 16 -1 (975 1300)(975 1350);
WIRE 16 -1 (975 1350)(1175 1350);
WIRE 16 -1 (975 1250)(975 1300);
WIRE 16 -1 (975 1300)(1175 1300);
WIRE 16 -1 (975 1200)(975 1250);
WIRE 16 -1 (975 1250)(1175 1250);
WIRE 16 -1 (975 1150)(975 1200);
WIRE 16 -1 (975 1200)(1175 1200);
WIRE 16 -1 (975 1100)(975 1150);
WIRE 16 -1 (975 1150)(1175 1150);
WIRE 16 -1 (975 1050)(975 1100);
WIRE 16 -1 (975 1100)(1175 1100);
WIRE 16 -1 (975 1000)(975 1050);
WIRE 16 -1 (975 1050)(1175 1050);
WIRE 16 -1 (975 950)(975 1000);
WIRE 16 -1 (975 1000)(1175 1000);
WIRE 16 -1 (975 900)(975 950);
WIRE 16 -1 (975 950)(1175 950);
WIRE 16 -1 (975 850)(975 900);
WIRE 16 -1 (975 900)(1175 900);
WIRE 16 -1 (975 800)(975 850);
WIRE 16 -1 (975 850)(1175 850);
WIRE 16 -1 (975 800)(1175 800);
WIRE 16 -1 (825 2300)(825 2200);
WIRE 16 -1 (825 2200)(975 2200);
WIRE 16 -1 (975 2150)(975 2200);
WIRE 16 -1 (975 2200)(1175 2200);
WIRE 16 -1 (975 2150)(1175 2150);
WIRE 16 -1 (975 2600)(975 2500);
WIRE 16 -1 (975 2500)(975 2450);
WIRE 16 -1 (975 2500)(1175 2500);
WIRE 16 -1 (975 2400)(975 2450);
WIRE 16 -1 (975 2450)(1175 2450);
WIRE 16 -1 (975 2400)(975 2350);
WIRE 16 -1 (975 2400)(1175 2400);
WIRE 16 -1 (975 2350)(975 2300);
WIRE 16 -1 (975 2350)(1175 2350);
WIRE 16 -1 (975 2300)(1175 2300);
WIRE 16 -1 (2725 1000)(2725 1100);
WIRE 16 -1 (2725 1100)(2725 1150);
WIRE 16 -1 (2725 1100)(2925 1100);
WIRE 16 -1 (2725 1150)(2725 1200);
WIRE 16 -1 (2725 1150)(2925 1150);
WIRE 16 -1 (2725 1200)(2725 1250);
WIRE 16 -1 (2725 1200)(2925 1200);
WIRE 16 -1 (2725 1250)(2725 1300);
WIRE 16 -1 (2725 1250)(2925 1250);
WIRE 16 -1 (2725 1300)(2725 1350);
WIRE 16 -1 (2725 1300)(2925 1300);
WIRE 16 -1 (2725 1350)(2725 1400);
WIRE 16 -1 (2725 1350)(2925 1350);
WIRE 16 -1 (2725 1400)(2725 1450);
WIRE 16 -1 (2725 1400)(2925 1400);
WIRE 16 -1 (2725 1450)(2725 1500);
WIRE 16 -1 (2725 1450)(2925 1450);
WIRE 16 -1 (2725 1500)(2725 1550);
WIRE 16 -1 (2725 1500)(2925 1500);
WIRE 16 -1 (2725 1550)(2725 1600);
WIRE 16 -1 (2725 1550)(2925 1550);
WIRE 16 -1 (2725 1600)(2725 1650);
WIRE 16 -1 (2725 1600)(2925 1600);
WIRE 16 -1 (2725 1650)(2725 1700);
WIRE 16 -1 (2725 1650)(2925 1650);
WIRE 16 -1 (2725 1700)(2725 1750);
WIRE 16 -1 (2725 1700)(2925 1700);
WIRE 16 -1 (2725 1750)(2725 1800);
WIRE 16 -1 (2725 1750)(2925 1750);
WIRE 16 -1 (2725 1800)(2725 1850);
WIRE 16 -1 (2725 1800)(2925 1800);
WIRE 16 -1 (2725 1850)(2725 1900);
WIRE 16 -1 (2725 1850)(2925 1850);
WIRE 16 -1 (2725 1900)(2725 1950);
WIRE 16 -1 (2725 1900)(2925 1900);
WIRE 16 -1 (2725 1950)(2725 2000);
WIRE 16 -1 (2725 1950)(2925 1950);
WIRE 16 -1 (2725 2000)(2725 2050);
WIRE 16 -1 (2725 2000)(2925 2000);
WIRE 16 -1 (2725 2050)(2725 2100);
WIRE 16 -1 (2725 2050)(2925 2050);
WIRE 16 -1 (2725 2100)(2725 2150);
WIRE 16 -1 (2725 2100)(2925 2100);
WIRE 16 -1 (2725 2150)(2725 2200);
WIRE 16 -1 (2725 2150)(2925 2150);
WIRE 16 -1 (2725 2200)(2725 2250);
WIRE 16 -1 (2725 2200)(2925 2200);
WIRE 16 -1 (2725 2250)(2725 2300);
WIRE 16 -1 (2725 2250)(2925 2250);
WIRE 16 -1 (2725 2300)(2725 2350);
WIRE 16 -1 (2725 2300)(2925 2300);
WIRE 16 -1 (2725 2350)(2725 2400);
WIRE 16 -1 (2725 2350)(2925 2350);
WIRE 16 -1 (2725 2400)(2725 2450);
WIRE 16 -1 (2725 2400)(2925 2400);
WIRE 16 -1 (2725 2450)(2725 2500);
WIRE 16 -1 (2725 2450)(2925 2450);
WIRE 16 -1 (2725 2500)(2725 2550);
WIRE 16 -1 (2725 2500)(2925 2500);
WIRE 16 -1 (2725 2550)(2725 2600);
WIRE 16 -1 (2725 2550)(2925 2550);
WIRE 16 -1 (2725 2600)(2725 2650);
WIRE 16 -1 (2725 2600)(2925 2600);
WIRE 16 -1 (2725 2650)(2725 2700);
WIRE 16 -1 (2725 2650)(2925 2650);
WIRE 16 -1 (2725 2700)(2725 2750);
WIRE 16 -1 (2725 2700)(2925 2700);
WIRE 16 -1 (2725 2750)(2725 2800);
WIRE 16 -1 (2725 2750)(2925 2750);
WIRE 16 -1 (2725 2800)(2725 2850);
WIRE 16 -1 (2725 2800)(2925 2800);
WIRE 16 -1 (2725 2850)(2725 2900);
WIRE 16 -1 (2725 2850)(2925 2850);
WIRE 16 -1 (2725 2900)(2725 2950);
WIRE 16 -1 (2725 2900)(2925 2900);
WIRE 16 -1 (2725 2950)(2725 3000);
WIRE 16 -1 (2725 2950)(2925 2950);
WIRE 16 -1 (2725 3000)(2725 3050);
WIRE 16 -1 (2725 3000)(2925 3000);
WIRE 16 -1 (2725 3050)(2725 3100);
WIRE 16 -1 (2725 3050)(2925 3050);
WIRE 16 -1 (2725 3100)(2725 3150);
WIRE 16 -1 (2725 3100)(2925 3100);
WIRE 16 -1 (2725 3150)(2725 3200);
WIRE 16 -1 (2725 3150)(2925 3150);
WIRE 16 -1 (2725 3200)(2725 3250);
WIRE 16 -1 (2725 3200)(2925 3200);
WIRE 16 -1 (2725 3250)(2725 3300);
WIRE 16 -1 (2725 3250)(2925 3250);
WIRE 16 -1 (2725 3300)(2725 3350);
WIRE 16 -1 (2725 3300)(2925 3300);
WIRE 16 -1 (2725 3350)(2725 3400);
WIRE 16 -1 (2725 3350)(2925 3350);
WIRE 16 -1 (2725 3400)(2925 3400);
WIRE 16 -1 (4125 1100)(4125 1000);
WIRE 16 -1 (4125 1150)(4125 1100);
WIRE 16 -1 (4125 1100)(3925 1100);
WIRE 16 -1 (4125 1200)(4125 1150);
WIRE 16 -1 (4125 1150)(3925 1150);
WIRE 16 -1 (4125 1250)(4125 1200);
WIRE 16 -1 (4125 1200)(3925 1200);
WIRE 16 -1 (4125 1300)(4125 1250);
WIRE 16 -1 (4125 1250)(3925 1250);
WIRE 16 -1 (4125 1350)(4125 1300);
WIRE 16 -1 (4125 1300)(3925 1300);
WIRE 16 -1 (4125 1400)(4125 1350);
WIRE 16 -1 (4125 1350)(3925 1350);
WIRE 16 -1 (4125 1450)(4125 1400);
WIRE 16 -1 (4125 1400)(3925 1400);
WIRE 16 -1 (4125 1500)(4125 1450);
WIRE 16 -1 (4125 1450)(3925 1450);
WIRE 16 -1 (4125 1550)(4125 1500);
WIRE 16 -1 (4125 1500)(3925 1500);
WIRE 16 -1 (4125 1600)(4125 1550);
WIRE 16 -1 (4125 1550)(3925 1550);
WIRE 16 -1 (4125 1650)(4125 1600);
WIRE 16 -1 (4125 1600)(3925 1600);
WIRE 16 -1 (4125 1700)(4125 1650);
WIRE 16 -1 (4125 1650)(3925 1650);
WIRE 16 -1 (4125 1750)(4125 1700);
WIRE 16 -1 (4125 1700)(3925 1700);
WIRE 16 -1 (4125 1800)(4125 1750);
WIRE 16 -1 (4125 1750)(3925 1750);
WIRE 16 -1 (4125 1850)(4125 1800);
WIRE 16 -1 (4125 1800)(3925 1800);
WIRE 16 -1 (4125 1900)(4125 1850);
WIRE 16 -1 (4125 1850)(3925 1850);
WIRE 16 -1 (4125 1950)(4125 1900);
WIRE 16 -1 (4125 1900)(3925 1900);
WIRE 16 -1 (4125 2000)(4125 1950);
WIRE 16 -1 (4125 1950)(3925 1950);
WIRE 16 -1 (4125 2050)(4125 2000);
WIRE 16 -1 (4125 2000)(3925 2000);
WIRE 16 -1 (4125 2100)(4125 2050);
WIRE 16 -1 (4125 2050)(3925 2050);
WIRE 16 -1 (4125 2150)(4125 2100);
WIRE 16 -1 (4125 2100)(3925 2100);
WIRE 16 -1 (4125 2200)(4125 2150);
WIRE 16 -1 (4125 2150)(3925 2150);
WIRE 16 -1 (4125 2250)(4125 2200);
WIRE 16 -1 (4125 2200)(3925 2200);
WIRE 16 -1 (4125 2300)(4125 2250);
WIRE 16 -1 (4125 2250)(3925 2250);
WIRE 16 -1 (4125 2350)(4125 2300);
WIRE 16 -1 (4125 2300)(3925 2300);
WIRE 16 -1 (4125 2400)(4125 2350);
WIRE 16 -1 (4125 2350)(3925 2350);
WIRE 16 -1 (4125 2450)(4125 2400);
WIRE 16 -1 (4125 2400)(3925 2400);
WIRE 16 -1 (4125 2500)(4125 2450);
WIRE 16 -1 (4125 2450)(3925 2450);
WIRE 16 -1 (4125 2550)(4125 2500);
WIRE 16 -1 (4125 2500)(3925 2500);
WIRE 16 -1 (4125 2600)(4125 2550);
WIRE 16 -1 (4125 2550)(3925 2550);
WIRE 16 -1 (4125 2650)(4125 2600);
WIRE 16 -1 (4125 2600)(3925 2600);
WIRE 16 -1 (4125 2700)(4125 2650);
WIRE 16 -1 (4125 2650)(3925 2650);
WIRE 16 -1 (4125 2700)(4125 2750);
WIRE 16 -1 (4125 2700)(3925 2700);
WIRE 16 -1 (4125 2800)(4125 2750);
WIRE 16 -1 (4125 2750)(3925 2750);
WIRE 16 -1 (4125 2800)(4125 2850);
WIRE 16 -1 (4125 2800)(3925 2800);
WIRE 16 -1 (4125 2850)(4125 2900);
WIRE 16 -1 (4125 2850)(3925 2850);
WIRE 16 -1 (4125 2900)(4125 2950);
WIRE 16 -1 (4125 2900)(3925 2900);
WIRE 16 -1 (4125 2950)(4125 3000);
WIRE 16 -1 (4125 2950)(3925 2950);
WIRE 16 -1 (4125 3000)(4125 3050);
WIRE 16 -1 (4125 3000)(3925 3000);
WIRE 16 -1 (4125 3050)(4125 3100);
WIRE 16 -1 (4125 3050)(3925 3050);
WIRE 16 -1 (4125 3100)(4125 3150);
WIRE 16 -1 (4125 3100)(3925 3100);
WIRE 16 -1 (4125 3150)(4125 3200);
WIRE 16 -1 (4125 3150)(3925 3150);
WIRE 16 -1 (4125 3200)(4125 3250);
WIRE 16 -1 (4125 3200)(3925 3200);
WIRE 16 -1 (4125 3250)(4125 3300);
WIRE 16 -1 (4125 3250)(3925 3250);
WIRE 16 -1 (4125 3300)(4125 3350);
WIRE 16 -1 (4125 3300)(3925 3300);
WIRE 16 -1 (4125 3350)(4125 3400);
WIRE 16 -1 (4125 3350)(3925 3350);
WIRE 16 -1 (4125 3400)(3925 3400);
WIRE 16 -1 (2375 2500)(2375 2675);
WIRE 16 -1 (2375 2450)(2375 2500);
WIRE 16 -1 (2175 2500)(2375 2500);
WIRE 16 -1 (2175 2450)(2375 2450);
WIRE 16 -1 (-3425 1400)(-3425 1300);
WIRE 16 -1 (-3425 1400)(-1325 1400);
WIRE 16 -1 (-3425 1550)(-3425 1450);
WIRE 16 -1 (-3425 1450)(-1475 1450);
WIRE 16 -1 (-1475 1350)(-1475 1450);
WIRE 16 -1 (-1475 1450)(-1325 1450);
WIRE 16 -1 (-1475 1350)(-1475 1300);
WIRE 16 -1 (-1325 1350)(-1475 1350);
WIRE 16 -1 (-1325 1300)(-1475 1300);
WIRE 17 -1 (-1625 2250)(-2175 2250);
FORCEPROP 2 LAST SIG_NAME M_B_ECC<7:0>
J 0
(-2150 2260);
DISPLAY 0.617021 (-2150 2260);
PAINT ORANGE (-2150 2260);
WIRE 17 -1 (-1625 2225)(-1625 2250);
WIRE 17 -1 (-1625 2175)(-1625 2225);
WIRE 17 -1 (-1625 2125)(-1625 2175);
WIRE 17 -1 (-1625 2075)(-1625 2125);
WIRE 17 -1 (-1625 2025)(-1625 2075);
WIRE 17 -1 (-1625 1975)(-1625 2025);
WIRE 17 -1 (-1625 1925)(-1625 1975);
WIRE 17 -1 (-1625 1875)(-1625 1925);
WIRE 17 -1 (425 4300)(-25 4300);
FORCEPROP 2 LAST SIG_NAME M_B_DQ<63:0>
J 0
(15 4310);
DISPLAY 0.617021 (15 4310);
PAINT ORANGE (15 4310);
WIRE 17 -1 (-25 4275)(-25 4300);
WIRE 17 -1 (-25 4225)(-25 4275);
WIRE 17 -1 (-25 4175)(-25 4225);
WIRE 17 -1 (-25 4125)(-25 4175);
WIRE 17 -1 (-25 4075)(-25 4125);
WIRE 17 -1 (-25 4025)(-25 4075);
WIRE 17 -1 (-25 3975)(-25 4025);
WIRE 17 -1 (-25 3925)(-25 3975);
WIRE 17 -1 (-25 3875)(-25 3925);
WIRE 17 -1 (-25 3825)(-25 3875);
WIRE 17 -1 (-25 3775)(-25 3825);
WIRE 17 -1 (-25 3725)(-25 3775);
WIRE 17 -1 (-25 3675)(-25 3725);
WIRE 17 -1 (-25 3625)(-25 3675);
WIRE 17 -1 (-25 3575)(-25 3625);
WIRE 17 -1 (-25 3525)(-25 3575);
WIRE 17 -1 (-25 3475)(-25 3525);
WIRE 17 -1 (-25 3425)(-25 3475);
WIRE 17 -1 (-25 3375)(-25 3425);
WIRE 17 -1 (-25 3325)(-25 3375);
WIRE 17 -1 (-25 3275)(-25 3325);
WIRE 17 -1 (-25 3225)(-25 3275);
WIRE 17 -1 (-25 3175)(-25 3225);
WIRE 17 -1 (-25 3125)(-25 3175);
WIRE 17 -1 (-25 3075)(-25 3125);
WIRE 17 -1 (-25 3025)(-25 3075);
WIRE 17 -1 (-25 2975)(-25 3025);
WIRE 17 -1 (-25 2925)(-25 2975);
WIRE 17 -1 (-25 2875)(-25 2925);
WIRE 17 -1 (-25 2825)(-25 2875);
WIRE 17 -1 (-25 2775)(-25 2825);
WIRE 17 -1 (-25 2725)(-25 2775);
WIRE 17 -1 (-25 2675)(-25 2725);
WIRE 17 -1 (-25 2625)(-25 2675);
WIRE 17 -1 (-25 2575)(-25 2625);
WIRE 17 -1 (-25 2525)(-25 2575);
WIRE 17 -1 (-25 2475)(-25 2525);
WIRE 17 -1 (-25 2425)(-25 2475);
WIRE 17 -1 (-25 2375)(-25 2425);
WIRE 17 -1 (-25 2325)(-25 2375);
WIRE 17 -1 (-25 2275)(-25 2325);
WIRE 17 -1 (-25 2225)(-25 2275);
WIRE 17 -1 (-25 2175)(-25 2225);
WIRE 17 -1 (-25 2125)(-25 2175);
WIRE 17 -1 (-25 2075)(-25 2125);
WIRE 17 -1 (-25 2025)(-25 2075);
WIRE 17 -1 (-25 1975)(-25 2025);
WIRE 17 -1 (-25 1925)(-25 1975);
WIRE 17 -1 (-25 1875)(-25 1925);
WIRE 17 -1 (-25 1825)(-25 1875);
WIRE 17 -1 (-25 1775)(-25 1825);
WIRE 17 -1 (-25 1725)(-25 1775);
WIRE 17 -1 (-25 1675)(-25 1725);
WIRE 17 -1 (-25 1625)(-25 1675);
WIRE 17 -1 (-25 1125)(-25 1175);
WIRE 17 -1 (-25 1175)(-25 1225);
WIRE 17 -1 (-25 1575)(-25 1625);
WIRE 17 -1 (-25 1525)(-25 1575);
WIRE 17 -1 (-25 1225)(-25 1275);
WIRE 17 -1 (-25 1275)(-25 1325);
WIRE 17 -1 (-25 1475)(-25 1525);
WIRE 17 -1 (-25 1425)(-25 1475);
WIRE 17 -1 (-25 1325)(-25 1375);
WIRE 17 -1 (-25 1375)(-25 1425);
WIRE 17 -1 (-1825 3100)(-2325 3100);
FORCEPROP 2 LAST SIG_NAME M_B_CLK_DN<3:0>
J 0
(-2275 3110);
DISPLAY 0.617021 (-2275 3110);
PAINT ORANGE (-2275 3110);
WIRE 17 -1 (-1825 3025)(-1825 3100);
WIRE 17 -1 (-1825 3025)(-1825 2925);
WIRE 17 -1 (-1625 2450)(-2175 2450);
FORCEPROP 2 LAST SIG_NAME M_B_ODT<3:0>
J 0
(-2150 2460);
DISPLAY 0.617021 (-2150 2460);
PAINT ORANGE (-2150 2460);
WIRE 17 -1 (-1625 2375)(-1625 2450);
WIRE 17 -1 (-1625 2325)(-1625 2375);
WIRE 17 -1 (-1625 2600)(-2175 2600);
FORCEPROP 2 LAST SIG_NAME M_B_CKE<3:0>
J 0
(-2150 2610);
DISPLAY 0.617021 (-2150 2610);
PAINT ORANGE (-2150 2610);
WIRE 17 -1 (-1625 2525)(-1625 2600);
WIRE 17 -1 (-1625 2475)(-1625 2525);
WIRE 17 -1 (-1625 2800)(-2175 2800);
FORCEPROP 2 LAST SIG_NAME M_B_CS_N<7:0>
J 0
(-2125 2810);
DISPLAY 0.617021 (-2125 2810);
PAINT ORANGE (-2125 2810);
WIRE 17 -1 (-1625 2775)(-1625 2800);
WIRE 17 -1 (-1625 2725)(-1625 2775);
WIRE 17 -1 (-1625 2675)(-1625 2725);
WIRE 17 -1 (-1625 2625)(-1625 2675);
WIRE 17 -1 (-1625 3150)(-2325 3150);
FORCEPROP 2 LAST SIG_NAME M_B_CLK_DP<3:0>
J 0
(-2275 3160);
DISPLAY 0.617021 (-2275 3160);
PAINT ORANGE (-2275 3160);
WIRE 17 -1 (-1625 2975)(-1625 3075);
WIRE 17 -1 (-1625 3075)(-1625 3150);
WIRE 17 -1 (-1625 3350)(-2175 3350);
FORCEPROP 2 LAST SIG_NAME M_B_BA<1:0>
J 0
(-2125 3360);
DISPLAY 0.617021 (-2125 3360);
PAINT ORANGE (-2125 3360);
WIRE 17 -1 (-1625 3350)(-1625 3325);
WIRE 17 -1 (-1625 3275)(-1625 3325);
WIRE 17 -1 (-1625 3250)(-2175 3250);
FORCEPROP 2 LAST SIG_NAME M_B_BG<1:0>
J 0
(-2125 3260);
DISPLAY 0.617021 (-2125 3260);
PAINT ORANGE (-2125 3260);
WIRE 17 -1 (-1625 3175)(-1625 3225);
WIRE 17 -1 (-1625 3225)(-1625 3250);
WIRE 17 -1 (-2175 4300)(-1625 4300);
FORCEPROP 2 LAST SIG_NAME M_B_MA<17:0>
J 0
(-2125 4310);
DISPLAY 0.617021 (-2125 4310);
PAINT ORANGE (-2125 4310);
WIRE 17 -1 (-1625 4275)(-1625 4300);
WIRE 17 -1 (-1625 4225)(-1625 4275);
WIRE 17 -1 (-1625 4175)(-1625 4225);
WIRE 17 -1 (-1625 4125)(-1625 4175);
WIRE 17 -1 (-1625 4075)(-1625 4125);
WIRE 17 -1 (-1625 4025)(-1625 4075);
WIRE 17 -1 (-1625 3975)(-1625 4025);
WIRE 17 -1 (-1625 3925)(-1625 3975);
WIRE 17 -1 (-1625 3875)(-1625 3925);
WIRE 17 -1 (-1625 3825)(-1625 3875);
WIRE 17 -1 (-1625 3775)(-1625 3825);
WIRE 17 -1 (-1625 3725)(-1625 3775);
WIRE 17 -1 (-1625 3675)(-1625 3725);
WIRE 17 -1 (-1625 3425)(-1625 3475);
WIRE 17 -1 (-1625 3625)(-1625 3675);
WIRE 17 -1 (-1625 3575)(-1625 3625);
WIRE 17 -1 (-1625 3475)(-1625 3525);
WIRE 17 -1 (-1625 3525)(-1625 3575);
WIRE 17 -1 (3175 4800)(2575 4800);
FORCEPROP 2 LAST SIG_NAME M_B_DQS_DN<17:0>
J 0
(2625 4810);
DISPLAY 0.617021 (2625 4810);
PAINT ORANGE (2625 4810);
WIRE 17 -1 (2575 4775)(2575 4800);
WIRE 17 -1 (2575 4675)(2575 4775);
WIRE 17 -1 (2575 4575)(2575 4675);
WIRE 17 -1 (2575 4475)(2575 4575);
WIRE 17 -1 (2575 4375)(2575 4475);
WIRE 17 -1 (2575 4275)(2575 4375);
WIRE 17 -1 (2575 4175)(2575 4275);
WIRE 17 -1 (2575 4075)(2575 4175);
WIRE 17 -1 (2575 3975)(2575 4075);
WIRE 17 -1 (2575 3875)(2575 3975);
WIRE 17 -1 (2575 3775)(2575 3875);
WIRE 17 -1 (2575 3675)(2575 3775);
WIRE 17 -1 (2575 3575)(2575 3675);
WIRE 17 -1 (2575 3475)(2575 3575);
WIRE 17 -1 (2575 3375)(2575 3475);
WIRE 17 -1 (2575 3275)(2575 3375);
WIRE 17 -1 (2575 3175)(2575 3275);
WIRE 17 -1 (2575 3075)(2575 3175);
WIRE 17 -1 (3175 4850)(2375 4850);
FORCEPROP 2 LAST SIG_NAME M_B_DQS_DP<17:0>
J 0
(2625 4860);
DISPLAY 0.617021 (2625 4860);
PAINT ORANGE (2625 4860);
WIRE 17 -1 (2375 4825)(2375 4850);
WIRE 17 -1 (2375 4725)(2375 4825);
WIRE 17 -1 (2375 4625)(2375 4725);
WIRE 17 -1 (2375 4525)(2375 4625);
WIRE 17 -1 (2375 4425)(2375 4525);
WIRE 17 -1 (2375 4325)(2375 4425);
WIRE 17 -1 (2375 4225)(2375 4325);
WIRE 17 -1 (2375 4125)(2375 4225);
WIRE 17 -1 (2375 4025)(2375 4125);
WIRE 17 -1 (2375 3925)(2375 4025);
WIRE 17 -1 (2375 3825)(2375 3925);
WIRE 17 -1 (2375 3725)(2375 3825);
WIRE 17 -1 (2375 3625)(2375 3725);
WIRE 17 -1 (2375 3125)(2375 3225);
WIRE 17 -1 (2375 3525)(2375 3625);
WIRE 17 -1 (2375 3425)(2375 3525);
WIRE 17 -1 (2375 3225)(2375 3325);
WIRE 17 -1 (2375 3325)(2375 3425);
WIRE 16 -1 (-125 3850)(-325 3850);
WIRE 16 -1 (2475 3850)(2075 3850);
WIRE 16 -1 (-125 1550)(-325 1550);
WIRE 16 -1 (-125 3800)(-325 3800);
WIRE 16 -1 (2275 4000)(2075 4000);
WIRE 16 -1 (2475 3750)(2075 3750);
WIRE 16 -1 (2475 3650)(2075 3650);
WIRE 16 -1 (2475 3550)(2075 3550);
WIRE 16 -1 (2475 3450)(2075 3450);
WIRE 16 -1 (2275 3400)(2075 3400);
WIRE 16 -1 (2475 4650)(2075 4650);
WIRE 16 -1 (2475 4750)(2075 4750);
WIRE 16 -1 (2275 4700)(2075 4700);
WIRE 16 -1 (2275 4800)(2075 4800);
WIRE 16 -1 (2475 4150)(2075 4150);
WIRE 16 -1 (2475 4250)(2075 4250);
WIRE 16 -1 (2475 4350)(2075 4350);
WIRE 16 -1 (2475 4450)(2075 4450);
WIRE 16 -1 (2475 4550)(2075 4550);
WIRE 16 -1 (2275 4400)(2075 4400);
WIRE 16 -1 (2275 4500)(2075 4500);
WIRE 16 -1 (2275 4600)(2075 4600);
WIRE 16 -1 (2275 4100)(2075 4100);
WIRE 16 -1 (2275 4200)(2075 4200);
WIRE 16 -1 (2275 4300)(2075 4300);
WIRE 16 -1 (2475 4050)(2075 4050);
WIRE 16 -1 (2475 3950)(2075 3950);
WIRE 16 -1 (2275 3900)(2075 3900);
WIRE 16 -1 (2275 3600)(2075 3600);
WIRE 16 -1 (2275 3700)(2075 3700);
WIRE 16 -1 (2275 3800)(2075 3800);
WIRE 16 -1 (2075 3150)(2475 3150);
WIRE 16 -1 (2075 3250)(2475 3250);
WIRE 16 -1 (2475 3350)(2075 3350);
WIRE 16 -1 (2275 3500)(2075 3500);
WIRE 16 -1 (2075 3100)(2275 3100);
WIRE 16 -1 (2075 3200)(2275 3200);
WIRE 16 -1 (2075 3300)(2275 3300);
WIRE 16 -1 (2075 3050)(2475 3050);
WIRE 16 -1 (-125 4250)(-325 4250);
WIRE 16 -1 (-125 4200)(-325 4200);
WIRE 16 -1 (-125 4150)(-325 4150);
WIRE 16 -1 (-125 4100)(-325 4100);
WIRE 16 -1 (-1325 4250)(-1525 4250);
WIRE 16 -1 (-1325 4100)(-1525 4100);
WIRE 16 -1 (-1325 4150)(-1525 4150);
WIRE 16 -1 (-1325 4200)(-1525 4200);
WIRE 16 -1 (-125 4050)(-325 4050);
WIRE 16 -1 (-125 3900)(-325 3900);
WIRE 16 -1 (-125 3950)(-325 3950);
WIRE 16 -1 (-125 4000)(-325 4000);
WIRE 16 -1 (-125 3750)(-325 3750);
WIRE 16 -1 (-125 3700)(-325 3700);
WIRE 16 -1 (-125 3650)(-325 3650);
WIRE 16 -1 (-125 3600)(-325 3600);
WIRE 16 -1 (-125 3400)(-325 3400);
WIRE 16 -1 (-125 3350)(-325 3350);
WIRE 16 -1 (-125 3300)(-325 3300);
WIRE 16 -1 (-125 3250)(-325 3250);
WIRE 16 -1 (-125 3200)(-325 3200);
WIRE 16 -1 (-125 3150)(-325 3150);
WIRE 16 -1 (-125 3100)(-325 3100);
WIRE 16 -1 (-125 3550)(-325 3550);
WIRE 16 -1 (-125 3500)(-325 3500);
WIRE 16 -1 (-125 3450)(-325 3450);
WIRE 16 -1 (-125 3050)(-325 3050);
WIRE 16 -1 (-125 2950)(-325 2950);
WIRE 16 -1 (-125 2800)(-325 2800);
WIRE 16 -1 (-125 2750)(-325 2750);
WIRE 16 -1 (-125 2700)(-325 2700);
WIRE 16 -1 (-125 2650)(-325 2650);
WIRE 16 -1 (-125 2600)(-325 2600);
WIRE 16 -1 (-125 2850)(-325 2850);
WIRE 16 -1 (-125 2900)(-325 2900);
WIRE 16 -1 (-125 3000)(-325 3000);
WIRE 16 -1 (-125 2550)(-325 2550);
WIRE 16 -1 (-125 2500)(-325 2500);
WIRE 16 -1 (-125 2350)(-325 2350);
WIRE 16 -1 (-125 2300)(-325 2300);
WIRE 16 -1 (-125 2250)(-325 2250);
WIRE 16 -1 (-125 2200)(-325 2200);
WIRE 16 -1 (-125 2150)(-325 2150);
WIRE 16 -1 (-125 2100)(-325 2100);
WIRE 16 -1 (-125 2050)(-325 2050);
WIRE 16 -1 (-125 2450)(-325 2450);
WIRE 16 -1 (-125 2400)(-325 2400);
WIRE 16 -1 (-1325 4000)(-1525 4000);
WIRE 16 -1 (-1325 4050)(-1525 4050);
WIRE 16 -1 (-1325 3850)(-1525 3850);
WIRE 16 -1 (-1325 3900)(-1525 3900);
WIRE 16 -1 (-1325 3950)(-1525 3950);
WIRE 16 -1 (-1325 3600)(-1525 3600);
WIRE 16 -1 (-1325 3700)(-1525 3700);
WIRE 16 -1 (-1325 3750)(-1525 3750);
WIRE 16 -1 (-1325 3800)(-1525 3800);
WIRE 16 -1 (-1325 3650)(-1525 3650);
WIRE 16 -1 (-1325 3400)(-1525 3400);
WIRE 16 -1 (-1325 3450)(-1525 3450);
WIRE 16 -1 (-1325 3550)(-1525 3550);
WIRE 16 -1 (-1325 3500)(-1525 3500);
WIRE 16 -1 (-1325 3300)(-1525 3300);
WIRE 16 -1 (-1325 3150)(-1525 3150);
WIRE 16 -1 (-1325 3200)(-1525 3200);
WIRE 16 -1 (-1325 3250)(-1525 3250);
WIRE 16 -1 (-1325 2950)(-1525 2950);
WIRE 16 -1 (-1325 3050)(-1525 3050);
WIRE 16 -1 (-1475 2800)(-1325 2800);
WIRE 16 -1 (-1475 2850)(-2175 2850);
FORCEPROP 2 LAST SIG_NAME M_B_C<2>
J 0
(-2125 2860);
DISPLAY 0.617021 (-2125 2860);
PAINT ORANGE (-2125 2860);
WIRE 16 -1 (-1475 2850)(-1475 2800);
WIRE 16 -1 (-1325 2750)(-1525 2750);
WIRE 16 -1 (-1325 2700)(-1525 2700);
WIRE 16 -1 (-1325 2650)(-1525 2650);
WIRE 16 -1 (-1325 2600)(-1525 2600);
WIRE 16 -1 (-1325 2500)(-1525 2500);
WIRE 16 -1 (-1325 2350)(-1525 2350);
WIRE 16 -1 (-1325 2450)(-1525 2450);
WIRE 16 -1 (-1325 2300)(-1525 2300);
WIRE 16 -1 (-1325 2150)(-1525 2150);
WIRE 16 -1 (-1325 2100)(-1525 2100);
WIRE 16 -1 (-1325 2050)(-1525 2050);
WIRE 16 -1 (-1325 2200)(-1525 2200);
WIRE 16 -1 (-1325 3000)(-1725 3000);
WIRE 16 -1 (-1325 2900)(-1725 2900);
WIRE 16 -1 (-1725 2150)(-2175 2150);
FORCEPROP 2 LAST SIG_NAME M_ABC_RST_N
J 0
(-2150 2160);
DISPLAY 0.617021 (-2150 2160);
PAINT ORANGE (-2150 2160);
WIRE 16 -1 (-1325 1700)(-1725 1700);
WIRE 16 -1 (-1725 1700)(-1725 2150);
WIRE 16 -1 (-1675 2200)(-2175 2200);
FORCEPROP 2 LAST SIG_NAME M_B_PAR
J 0
(-2150 2210);
DISPLAY 0.617021 (-2150 2210);
PAINT ORANGE (-2150 2210);
WIRE 16 -1 (-1325 1750)(-1675 1750);
WIRE 16 -1 (-1675 1750)(-1675 2200);
WIRE 16 -1 (-125 2000)(-325 2000);
WIRE 16 -1 (-125 1900)(-325 1900);
WIRE 16 -1 (-125 1800)(-325 1800);
WIRE 16 -1 (-125 1750)(-325 1750);
WIRE 16 -1 (-125 1700)(-325 1700);
WIRE 16 -1 (-125 1650)(-325 1650);
WIRE 16 -1 (-125 1600)(-325 1600);
WIRE 16 -1 (-125 1850)(-325 1850);
WIRE 16 -1 (-125 1950)(-325 1950);
WIRE 16 -1 (-125 1150)(-325 1150);
WIRE 16 -1 (-125 1500)(-325 1500);
WIRE 16 -1 (-125 1450)(-325 1450);
WIRE 16 -1 (-125 1400)(-325 1400);
WIRE 16 -1 (-125 1100)(-325 1100);
WIRE 16 -1 (-125 1200)(-325 1200);
WIRE 16 -1 (-125 1250)(-325 1250);
WIRE 16 -1 (-125 1300)(-325 1300);
WIRE 16 -1 (-125 1350)(-325 1350);
WIRE 16 -1 (-1325 2000)(-1525 2000);
WIRE 16 -1 (-1325 1950)(-1525 1950);
WIRE 16 -1 (-1325 1900)(-1525 1900);
WIRE 16 -1 (-1325 1850)(-1525 1850);
WIRE 16 -1 (-1775 1950)(-2500 1950);
FORCEPROP 2 LAST SIG_NAME FM_DIMM_EVENT_COD_N
J 0
(-2506 1972);
DISPLAY 0.617021 (-2506 1972);
PAINT ORANGE (-2506 1972);
WIRE 16 -1 (-1775 1650)(-1775 1950);
WIRE 16 -1 (-1775 1650)(-1325 1650);
WIRE 16 -1 (-1325 1550)(-2325 1550);
FORCEPROP 2 LAST SIG_NAME M_B_ACT_N
J 0
(-2275 1560);
DISPLAY 0.617021 (-2275 1560);
PAINT ORANGE (-2275 1560);
WIRE 16 -1 (-1325 1600)(-2350 1600);
FORCEPROP 2 LAST SIG_NAME M_B_ALERT_N
J 0
(-2300 1610);
DISPLAY 0.617021 (-2300 1610);
PAINT ORANGE (-2300 1610);
WIRE 16 -1 (-1325 1250)(-2175 1250);
WIRE 16 -1 (-2175 1200)(-1325 1200);
FORCEPROP 2 LAST SIG_NAME SMB_DDR_ABC_VPP_SCL
J 0
(-2135 1210);
DISPLAY 0.617021 (-2135 1210);
PAINT ORANGE (-2135 1210);
WIRE 16 -1 (-2175 800)(-1325 800);
FORCEPROP 2 LAST SIG_NAME FM_ADR_COMPLETE_ABC_N
J 0
(-2125 810);
DISPLAY 0.617021 (-2125 810);
PAINT ORANGE (-2125 810);
WIRE 16 -1 (-2175 1000)(-1325 1000);
FORCEPROP 2 LAST SIG_NAME TP_CH_B_DIMM_B1_RFU_2
J 0
(-2125 1010);
DISPLAY 0.617021 (-2125 1010);
PAINT ORANGE (-2125 1010);
FORCEPROP 2 LASTPROP $XRERR UNIQUE?
J 0
(-2415 1000);
DISPLAY 0.638298 (-2415 1000);
PAINT MONO (-2415 1000);
DISPLAY INVISIBLE (-2415 1000);
WIRE 16 -1 (-2175 900)(-1325 900);
FORCEPROP 2 LAST SIG_NAME TP_CH_B_DIMM_B1_RFU_0
J 0
(-2125 910);
DISPLAY 0.617021 (-2125 910);
PAINT ORANGE (-2125 910);
FORCEPROP 2 LASTPROP $XRERR UNIQUE?
J 0
(-2415 900);
DISPLAY 0.638298 (-2415 900);
PAINT MONO (-2415 900);
DISPLAY INVISIBLE (-2415 900);
WIRE 16 -1 (-2175 950)(-1325 950);
FORCEPROP 2 LAST SIG_NAME TP_CH_B_DIMM_B1_RFU_1
J 0
(-2125 960);
DISPLAY 0.617021 (-2125 960);
PAINT ORANGE (-2125 960);
FORCEPROP 2 LASTPROP $XRERR UNIQUE?
J 0
(-2415 950);
DISPLAY 0.638298 (-2415 950);
PAINT MONO (-2415 950);
DISPLAY INVISIBLE (-2415 950);
WIRE 16 -1 (-3075 1100)(-2975 1100);
WIRE 16 -1 (-2975 1000)(-2975 1100);
WIRE 16 -1 (-1325 1100)(-2975 1100);
FORCEPROP 2 LAST SIG_NAME M_B_VREF
J 0
(-2125 1110);
DISPLAY 0.617021 (-2125 1110);
PAINT ORANGE (-2125 1110);
DOT 1 (2725 2300);
DOT 1 (4125 2650);
DOT 1 (975 1950);
DOT 1 (4125 3350);
DOT 1 (4125 3300);
DOT 1 (4125 3250);
DOT 1 (4125 3200);
DOT 1 (4125 3150);
DOT 1 (4125 3000);
DOT 1 (4125 3050);
DOT 1 (4125 3100);
DOT 1 (4125 2950);
DOT 1 (4125 2900);
DOT 1 (4125 2850);
DOT 1 (4125 2750);
DOT 1 (4125 2800);
DOT 1 (4125 2700);
DOT 1 (4125 2600);
DOT 1 (4125 2550);
DOT 1 (4125 2500);
DOT 1 (4125 2400);
DOT 1 (4125 2450);
DOT 1 (4125 2350);
DOT 1 (4125 2250);
DOT 1 (4125 2300);
DOT 1 (4125 2100);
DOT 1 (4125 2150);
DOT 1 (4125 2200);
DOT 1 (4125 2050);
DOT 1 (4125 2000);
DOT 1 (4125 1850);
DOT 1 (4125 1900);
DOT 1 (4125 1950);
DOT 1 (4125 1750);
DOT 1 (4125 1800);
DOT 1 (4125 1700);
DOT 1 (4125 1650);
DOT 1 (4125 1600);
DOT 1 (4125 1500);
DOT 1 (4125 1550);
DOT 1 (4125 1450);
DOT 1 (4125 1400);
DOT 1 (4125 1350);
DOT 1 (4125 1200);
DOT 1 (4125 1250);
DOT 1 (4125 1300);
DOT 1 (4125 1150);
DOT 1 (4125 1100);
DOT 1 (2725 3350);
DOT 1 (2725 3300);
DOT 1 (2725 3250);
DOT 1 (2725 3200);
DOT 1 (2725 3150);
DOT 1 (2725 3000);
DOT 1 (2725 3050);
DOT 1 (2725 3100);
DOT 1 (2725 2950);
DOT 1 (2725 2900);
DOT 1 (2725 2850);
DOT 1 (2725 2750);
DOT 1 (2725 2800);
DOT 1 (2725 2650);
DOT 1 (2725 2700);
DOT 1 (2725 2550);
DOT 1 (2725 2400);
DOT 1 (2725 2450);
DOT 1 (2725 2350);
DOT 1 (2725 2250);
DOT 1 (2725 2150);
DOT 1 (2725 2100);
DOT 1 (2725 2200);
DOT 1 (2725 2050);
DOT 1 (2725 2000);
DOT 1 (2725 1850);
DOT 1 (2725 1900);
DOT 1 (2725 1950);
DOT 1 (2725 1750);
DOT 1 (2725 1800);
DOT 1 (2375 2500);
DOT 1 (2725 1700);
DOT 1 (2725 1650);
DOT 1 (2725 1600);
DOT 1 (2725 1500);
DOT 1 (2725 1550);
DOT 1 (2725 1450);
DOT 1 (2725 1400);
DOT 1 (2725 1350);
DOT 1 (2725 1250);
DOT 1 (2725 1200);
DOT 1 (2725 1300);
DOT 1 (2725 1150);
DOT 1 (2725 1100);
DOT 1 (975 2500);
DOT 1 (975 2450);
DOT 1 (975 2400);
DOT 1 (975 2350);
DOT 1 (975 2000);
DOT 1 (975 2200);
DOT 1 (975 1850);
DOT 1 (975 1900);
DOT 1 (975 1800);
DOT 1 (975 1750);
DOT 1 (975 1700);
DOT 1 (975 1600);
DOT 1 (975 1650);
DOT 1 (975 1550);
DOT 1 (975 1500);
DOT 1 (975 1450);
DOT 1 (975 1350);
DOT 1 (975 1400);
DOT 1 (975 1300);
DOT 1 (975 1250);
DOT 1 (975 1200);
DOT 1 (975 1100);
DOT 1 (975 1150);
DOT 1 (975 1050);
DOT 1 (975 1000);
DOT 1 (975 950);
DOT 1 (-2975 1100);
DOT 1 (-1475 1450);
DOT 1 (-1475 1350);
DOT 1 (975 900);
DOT 1 (975 850);
DOT 1 (2725 2500);
DOT 1 (2725 2600);
DOT 1 (975 2050);
FORCENOTE
PVDDQ (SINGLE SIDE) CAP: 10UF X1, 22UF X50
(-2400 4800) 0;
DISPLAY LEFT (-2400 4800);
DISPLAY 1.021277 (-2400 4800);
PAINT PURPLE (-2400 4800);
FORCENOTE
PVDDQ (DOUBLE SIDE) CAP: 100UF X8, 47UF X41
(-2400 4750) 0;
DISPLAY LEFT (-2400 4750);
DISPLAY 1.021277 (-2400 4750);
PAINT PURPLE (-2400 4750);
FORCENOTE
PVTT CAP: 100UF X2, 47UF X1
(-2400 4850) 0;
DISPLAY LEFT (-2400 4850);
DISPLAY 1.021277 (-2400 4850);
PAINT PURPLE (-2400 4850);
FORCENOTE
PVPP CAP: 10UF X12
(-2400 4900) 0;
DISPLAY LEFT (-2400 4900);
DISPLAY 1.021277 (-2400 4900);
PAINT PURPLE (-2400 4900);
FORCENOTE
PLACE CAP NEAR DIMM CONNECTOR
(-3679 550) 0;
DISPLAY LEFT (-3679 550);
DISPLAY 1.595745 (-3679 550);
PAINT PURPLE (-3679 550);
FORCENOTE
SMBUS ADDR: 0XA6
(-3692 387) 0;
DISPLAY LEFT (-3692 387);
DISPLAY 1.957447 (-3692 387);
PAINT PURPLE (-3692 387);
FORCENOTE
CAP BETWEEN DIMM
(-2400 4975) 0;
DISPLAY LEFT (-2400 4975);
DISPLAY 1.276596 (-2400 4975);
PAINT PURPLE (-2400 4975);
QUIT
